(kicad_sch
	(version 20250114)
	(generator "eeschema")
	(generator_version "9.0")
	(paper "A3")
	(title_block
		(title "GMSL Deserializer")
		(date "2025-10-09")
		(rev "1.0.4")
		(company "Antmicro Ltd")
		(comment 1 "www.antmicro.com")
	)
	(bus_alias "CSI"
		(members "CLK_N" "CLK_P" "D0_N" "D0_P" "D1_N" "D1_P" "D2_N" "D2_P" "D3_N"
			"D3_P"
		)
	)
	(text "Crystal"
		(exclude_from_sim no)
		(at 44.45 157.48 0)
		(effects
			(font
				(size 4 4)
				(thickness 0.8)
				(bold yes)
			)
			(justify left bottom)
		)
	)
	(text "Link-Isolation capacitors and ESD diodes"
		(exclude_from_sim no)
		(at 39.37 82.55 0)
		(effects
			(font
				(size 4 4)
				(thickness 0.8)
				(bold yes)
			)
			(justify left bottom)
		)
	)
	(text "GMSL2 Mode - 0.1 uF\nGMSL1 Mode, HIM Disabled - 0.22 uF\nGMSL1 Mode, HIM Enabled - 0.047 to 0.22 uF"
		(exclude_from_sim no)
		(at 86.36 93.345 0)
		(effects
			(font
				(size 1.27 1.27)
			)
			(justify right bottom)
		)
	)
	(text "CFG1 - GMSL mode config\nR1 = OPEN, R2 = 10k\nmode = COAX GMSL2 6Gbps"
		(exclude_from_sim no)
		(at 151.13 167.64 0)
		(effects
			(font
				(size 1.27 1.27)
			)
			(justify left bottom)
		)
	)
	(text "CFG0 - I2C address config\nR1 = OPEN, R2 = 10k\naddress = 0x4E"
		(exclude_from_sim no)
		(at 113.03 167.64 0)
		(effects
			(font
				(size 1.27 1.27)
			)
			(justify left bottom)
		)
	)
	(text "Config pins"
		(exclude_from_sim no)
		(at 127 157.48 0)
		(effects
			(font
				(size 4 4)
				(thickness 0.8)
				(bold yes)
			)
			(justify left bottom)
		)
	)
	(text "Cinx1 = 3 pF (from MAX96724 data sheet)\nCtrace = 2 pF (estimated)\nCinx2 = 1 pF (from MAX96724 data sheet)\nCL = 18 pF (from crystal data sheet)\nCx1total = Cinx1 + CL1 + Ctrace\nCx2total = Cinx2 + CL2 + Ctrace\nCL = (Cx1total * Cx2total) / (Cx1total + Cx2total)\n\nCl1 = Cl2 = 33 pF\nCx1total = 38 pF, Cx2total = 36 pF\nCL = 18.5 pF"
		(exclude_from_sim no)
		(at 69.215 189.865 0)
		(effects
			(font
				(size 1.27 1.27)
			)
			(justify right bottom)
		)
	)
	(text "Deserializer IC with passives"
		(exclude_from_sim no)
		(at 254 81.28 0)
		(effects
			(font
				(size 4 4)
				(thickness 0.8)
				(bold yes)
			)
			(justify left bottom)
		)
	)
	(junction
		(at 251.46 115.57)
		(diameter 0)
		(color 0 0 0 0)
	)
	(junction
		(at 261.62 96.52)
		(diameter 0)
		(color 0 0 0 0)
	)
	(junction
		(at 121.92 114.3)
		(diameter 0)
		(color 0 0 0 0)
	)
	(junction
		(at 121.92 185.42)
		(diameter 0)
		(color 0 0 0 0)
	)
	(junction
		(at 326.39 96.52)
		(diameter 0)
		(color 0 0 0 0)
	)
	(junction
		(at 261.62 115.57)
		(diameter 0)
		(color 0 0 0 0)
	)
	(junction
		(at 360.68 96.52)
		(diameter 0)
		(color 0 0 0 0)
	)
	(junction
		(at 102.87 99.06)
		(diameter 0)
		(color 0 0 0 0)
	)
	(junction
		(at 127 119.38)
		(diameter 0)
		(color 0 0 0 0)
	)
	(junction
		(at 242.57 96.52)
		(diameter 0)
		(color 0 0 0 0)
	)
	(junction
		(at 162.56 185.42)
		(diameter 0)
		(color 0 0 0 0)
	)
	(junction
		(at 251.46 96.52)
		(diameter 0)
		(color 0 0 0 0)
	)
	(junction
		(at 361.95 118.11)
		(diameter 0)
		(color 0 0 0 0)
	)
	(junction
		(at 320.04 96.52)
		(diameter 0)
		(color 0 0 0 0)
	)
	(junction
		(at 77.47 182.88)
		(diameter 0)
		(color 0 0 0 0)
	)
	(junction
		(at 353.06 118.11)
		(diameter 0)
		(color 0 0 0 0)
	)
	(junction
		(at 242.57 115.57)
		(diameter 0)
		(color 0 0 0 0)
	)
	(junction
		(at 342.9 118.11)
		(diameter 0)
		(color 0 0 0 0)
	)
	(junction
		(at 232.41 96.52)
		(diameter 0)
		(color 0 0 0 0)
	)
	(junction
		(at 252.73 194.31)
		(diameter 0)
		(color 0 0 0 0)
	)
	(junction
		(at 107.95 104.14)
		(diameter 0)
		(color 0 0 0 0)
	)
	(junction
		(at 91.44 182.88)
		(diameter 0)
		(color 0 0 0 0)
	)
	(junction
		(at 223.52 115.57)
		(diameter 0)
		(color 0 0 0 0)
	)
	(junction
		(at 341.63 96.52)
		(diameter 0)
		(color 0 0 0 0)
	)
	(junction
		(at 223.52 96.52)
		(diameter 0)
		(color 0 0 0 0)
	)
	(junction
		(at 119.38 111.76)
		(diameter 0)
		(color 0 0 0 0)
	)
	(junction
		(at 243.84 194.31)
		(diameter 0)
		(color 0 0 0 0)
	)
	(junction
		(at 100.33 96.52)
		(diameter 0)
		(color 0 0 0 0)
	)
	(junction
		(at 351.79 96.52)
		(diameter 0)
		(color 0 0 0 0)
	)
	(junction
		(at 85.09 189.23)
		(diameter 0)
		(color 0 0 0 0)
	)
	(junction
		(at 105.41 106.68)
		(diameter 0)
		(color 0 0 0 0)
	)
	(junction
		(at 232.41 115.57)
		(diameter 0)
		(color 0 0 0 0)
	)
	(junction
		(at 124.46 121.92)
		(diameter 0)
		(color 0 0 0 0)
	)
	(junction
		(at 236.22 194.31)
		(diameter 0)
		(color 0 0 0 0)
	)
	(no_connect
		(at 316.23 133.35)
	)
	(no_connect
		(at 316.23 171.45)
	)
	(no_connect
		(at 316.23 135.89)
	)
	(no_connect
		(at 316.23 173.99)
	)
	(bus_entry
		(at 330.2 140.97)
		(size 1.27 1.27)
		(stroke
			(width 0)
			(type default)
		)
	)
	(bus_entry
		(at 273.05 161.29)
		(size -1.27 1.27)
		(stroke
			(width 0)
			(type default)
		)
	)
	(bus_entry
		(at 330.2 179.07)
		(size 1.27 1.27)
		(stroke
			(width 0)
			(type default)
		)
	)
	(bus_entry
		(at 273.05 173.99)
		(size -1.27 1.27)
		(stroke
			(width 0)
			(type default)
		)
	)
	(bus_entry
		(at 273.05 181.61)
		(size -1.27 1.27)
		(stroke
			(width 0)
			(type default)
		)
	)
	(bus_entry
		(at 330.2 176.53)
		(size 1.27 1.27)
		(stroke
			(width 0)
			(type default)
		)
	)
	(bus_entry
		(at 330.2 194.31)
		(size 1.27 1.27)
		(stroke
			(width 0)
			(type default)
		)
	)
	(bus_entry
		(at 330.2 148.59)
		(size 1.27 1.27)
		(stroke
			(width 0)
			(type default)
		)
	)
	(bus_entry
		(at 330.2 138.43)
		(size 1.27 1.27)
		(stroke
			(width 0)
			(type default)
		)
	)
	(bus_entry
		(at 330.2 181.61)
		(size 1.27 1.27)
		(stroke
			(width 0)
			(type default)
		)
	)
	(bus_entry
		(at 330.2 184.15)
		(size 1.27 1.27)
		(stroke
			(width 0)
			(type default)
		)
	)
	(bus_entry
		(at 330.2 186.69)
		(size 1.27 1.27)
		(stroke
			(width 0)
			(type default)
		)
	)
	(bus_entry
		(at 273.05 166.37)
		(size -1.27 1.27)
		(stroke
			(width 0)
			(type default)
		)
	)
	(bus_entry
		(at 273.05 168.91)
		(size -1.27 1.27)
		(stroke
			(width 0)
			(type default)
		)
	)
	(bus_entry
		(at 330.2 156.21)
		(size 1.27 1.27)
		(stroke
			(width 0)
			(type default)
		)
	)
	(bus_entry
		(at 273.05 179.07)
		(size -1.27 1.27)
		(stroke
			(width 0)
			(type default)
		)
	)
	(bus_entry
		(at 330.2 191.77)
		(size 1.27 1.27)
		(stroke
			(width 0)
			(type default)
		)
	)
	(bus_entry
		(at 273.05 163.83)
		(size -1.27 1.27)
		(stroke
			(width 0)
			(type default)
		)
	)
	(bus_entry
		(at 330.2 189.23)
		(size 1.27 1.27)
		(stroke
			(width 0)
			(type default)
		)
	)
	(bus_entry
		(at 330.2 153.67)
		(size 1.27 1.27)
		(stroke
			(width 0)
			(type default)
		)
	)
	(bus_entry
		(at 330.2 161.29)
		(size 1.27 1.27)
		(stroke
			(width 0)
			(type default)
		)
	)
	(bus_entry
		(at 330.2 199.39)
		(size 1.27 1.27)
		(stroke
			(width 0)
			(type default)
		)
	)
	(bus_entry
		(at 273.05 171.45)
		(size -1.27 1.27)
		(stroke
			(width 0)
			(type default)
		)
	)
	(bus_entry
		(at 330.2 196.85)
		(size 1.27 1.27)
		(stroke
			(width 0)
			(type default)
		)
	)
	(bus_entry
		(at 330.2 151.13)
		(size 1.27 1.27)
		(stroke
			(width 0)
			(type default)
		)
	)
	(bus_entry
		(at 330.2 146.05)
		(size 1.27 1.27)
		(stroke
			(width 0)
			(type default)
		)
	)
	(bus_entry
		(at 330.2 143.51)
		(size 1.27 1.27)
		(stroke
			(width 0)
			(type default)
		)
	)
	(bus_entry
		(at 330.2 158.75)
		(size 1.27 1.27)
		(stroke
			(width 0)
			(type default)
		)
	)
	(polyline
		(pts
			(xy 12.065 213.995) (xy 187.96 213.995)
		)
		(stroke
			(width 0)
			(type dash)
		)
	)
	(wire
		(pts
			(xy 223.52 96.52) (xy 232.41 96.52)
		)
		(stroke
			(width 0)
			(type default)
		)
	)
	(wire
		(pts
			(xy 113.03 125.73) (xy 116.84 125.73)
		)
		(stroke
			(width 0)
			(type default)
		)
	)
	(wire
		(pts
			(xy 342.9 118.11) (xy 342.9 119.38)
		)
		(stroke
			(width 0)
			(type default)
		)
	)
	(wire
		(pts
			(xy 252.73 201.93) (xy 252.73 200.66)
		)
		(stroke
			(width 0)
			(type default)
		)
	)
	(wire
		(pts
			(xy 236.22 201.93) (xy 236.22 200.66)
		)
		(stroke
			(width 0)
			(type default)
		)
	)
	(wire
		(pts
			(xy 127 119.38) (xy 134.62 119.38)
		)
		(stroke
			(width 0)
			(type default)
		)
	)
	(wire
		(pts
			(xy 316.23 153.67) (xy 330.2 153.67)
		)
		(stroke
			(width 0)
			(type default)
		)
	)
	(wire
		(pts
			(xy 316.23 199.39) (xy 330.2 199.39)
		)
		(stroke
			(width 0)
			(type default)
		)
	)
	(wire
		(pts
			(xy 271.78 125.73) (xy 280.67 125.73)
		)
		(stroke
			(width 0)
			(type default)
		)
	)
	(wire
		(pts
			(xy 351.79 97.79) (xy 351.79 96.52)
		)
		(stroke
			(width 0)
			(type default)
		)
	)
	(wire
		(pts
			(xy 353.06 119.38) (xy 353.06 118.11)
		)
		(stroke
			(width 0)
			(type default)
		)
	)
	(wire
		(pts
			(xy 261.62 104.14) (xy 261.62 102.87)
		)
		(stroke
			(width 0)
			(type default)
		)
	)
	(wire
		(pts
			(xy 63.5 96.52) (xy 81.28 96.52)
		)
		(stroke
			(width 0)
			(type default)
		)
	)
	(bus
		(pts
			(xy 331.47 201.93) (xy 332.74 203.2)
		)
		(stroke
			(width 0)
			(type default)
		)
	)
	(wire
		(pts
			(xy 85.09 190.5) (xy 85.09 189.23)
		)
		(stroke
			(width 0)
			(type default)
		)
	)
	(wire
		(pts
			(xy 252.73 194.31) (xy 280.67 194.31)
		)
		(stroke
			(width 0)
			(type default)
		)
	)
	(wire
		(pts
			(xy 351.79 104.14) (xy 351.79 102.87)
		)
		(stroke
			(width 0)
			(type default)
		)
	)
	(bus
		(pts
			(xy 331.47 193.04) (xy 331.47 195.58)
		)
		(stroke
			(width 0)
			(type default)
		)
	)
	(bus
		(pts
			(xy 271.78 184.15) (xy 270.51 185.42)
		)
		(stroke
			(width 0)
			(type default)
		)
	)
	(wire
		(pts
			(xy 278.13 189.23) (xy 280.67 189.23)
		)
		(stroke
			(width 0)
			(type default)
		)
	)
	(wire
		(pts
			(xy 261.62 115.57) (xy 280.67 115.57)
		)
		(stroke
			(width 0)
			(type default)
		)
	)
	(polyline
		(pts
			(xy 12.065 146.05) (xy 187.96 146.05)
		)
		(stroke
			(width 0)
			(type dash)
		)
	)
	(wire
		(pts
			(xy 370.84 95.25) (xy 370.84 96.52)
		)
		(stroke
			(width 0)
			(type default)
		)
	)
	(wire
		(pts
			(xy 271.78 148.59) (xy 280.67 148.59)
		)
		(stroke
			(width 0)
			(type default)
		)
	)
	(wire
		(pts
			(xy 121.92 171.45) (xy 121.92 177.8)
		)
		(stroke
			(width 0)
			(type default)
		)
	)
	(wire
		(pts
			(xy 227.33 194.31) (xy 227.33 195.58)
		)
		(stroke
			(width 0)
			(type default)
		)
	)
	(wire
		(pts
			(xy 214.63 96.52) (xy 223.52 96.52)
		)
		(stroke
			(width 0)
			(type default)
		)
	)
	(wire
		(pts
			(xy 102.87 99.06) (xy 102.87 127)
		)
		(stroke
			(width 0)
			(type default)
		)
	)
	(wire
		(pts
			(xy 271.78 133.35) (xy 280.67 133.35)
		)
		(stroke
			(width 0)
			(type default)
		)
	)
	(wire
		(pts
			(xy 316.23 113.03) (xy 320.04 113.03)
		)
		(stroke
			(width 0)
			(type default)
		)
	)
	(wire
		(pts
			(xy 326.39 115.57) (xy 326.39 110.49)
		)
		(stroke
			(width 0)
			(type default)
		)
	)
	(wire
		(pts
			(xy 63.5 119.38) (xy 81.28 119.38)
		)
		(stroke
			(width 0)
			(type default)
		)
	)
	(wire
		(pts
			(xy 232.41 97.79) (xy 232.41 96.52)
		)
		(stroke
			(width 0)
			(type default)
		)
	)
	(polyline
		(pts
			(xy 187.96 146.05) (xy 187.96 70.485)
		)
		(stroke
			(width 0)
			(type dash)
		)
	)
	(wire
		(pts
			(xy 316.23 161.29) (xy 330.2 161.29)
		)
		(stroke
			(width 0)
			(type default)
		)
	)
	(wire
		(pts
			(xy 243.84 194.31) (xy 252.73 194.31)
		)
		(stroke
			(width 0)
			(type default)
		)
	)
	(bus
		(pts
			(xy 331.47 187.96) (xy 331.47 190.5)
		)
		(stroke
			(width 0)
			(type default)
		)
	)
	(wire
		(pts
			(xy 273.05 173.99) (xy 280.67 173.99)
		)
		(stroke
			(width 0)
			(type default)
		)
	)
	(bus
		(pts
			(xy 331.47 160.02) (xy 331.47 162.56)
		)
		(stroke
			(width 0)
			(type default)
		)
	)
	(wire
		(pts
			(xy 227.33 194.31) (xy 236.22 194.31)
		)
		(stroke
			(width 0)
			(type default)
		)
	)
	(wire
		(pts
			(xy 223.52 96.52) (xy 223.52 97.79)
		)
		(stroke
			(width 0)
			(type default)
		)
	)
	(wire
		(pts
			(xy 316.23 176.53) (xy 330.2 176.53)
		)
		(stroke
			(width 0)
			(type default)
		)
	)
	(wire
		(pts
			(xy 360.68 96.52) (xy 370.84 96.52)
		)
		(stroke
			(width 0)
			(type default)
		)
	)
	(wire
		(pts
			(xy 316.23 115.57) (xy 326.39 115.57)
		)
		(stroke
			(width 0)
			(type default)
		)
	)
	(wire
		(pts
			(xy 353.06 118.11) (xy 342.9 118.11)
		)
		(stroke
			(width 0)
			(type default)
		)
	)
	(wire
		(pts
			(xy 273.05 166.37) (xy 280.67 166.37)
		)
		(stroke
			(width 0)
			(type default)
		)
	)
	(wire
		(pts
			(xy 93.98 125.73) (xy 97.79 125.73)
		)
		(stroke
			(width 0)
			(type default)
		)
	)
	(wire
		(pts
			(xy 91.44 106.68) (xy 105.41 106.68)
		)
		(stroke
			(width 0)
			(type default)
		)
	)
	(bus
		(pts
			(xy 331.47 200.66) (xy 331.47 201.93)
		)
		(stroke
			(width 0)
			(type default)
		)
	)
	(wire
		(pts
			(xy 86.36 119.38) (xy 127 119.38)
		)
		(stroke
			(width 0)
			(type default)
		)
	)
	(wire
		(pts
			(xy 77.47 182.88) (xy 81.28 182.88)
		)
		(stroke
			(width 0)
			(type default)
		)
	)
	(bus
		(pts
			(xy 271.78 175.26) (xy 271.78 180.34)
		)
		(stroke
			(width 0)
			(type default)
		)
	)
	(bus
		(pts
			(xy 331.47 157.48) (xy 331.47 160.02)
		)
		(stroke
			(width 0)
			(type default)
		)
	)
	(bus
		(pts
			(xy 271.78 162.56) (xy 271.78 165.1)
		)
		(stroke
			(width 0)
			(type default)
		)
	)
	(wire
		(pts
			(xy 316.23 118.11) (xy 342.9 118.11)
		)
		(stroke
			(width 0)
			(type default)
		)
	)
	(wire
		(pts
			(xy 121.92 114.3) (xy 134.62 114.3)
		)
		(stroke
			(width 0)
			(type default)
		)
	)
	(bus
		(pts
			(xy 331.47 142.24) (xy 331.47 144.78)
		)
		(stroke
			(width 0)
			(type default)
		)
	)
	(bus
		(pts
			(xy 332.74 203.2) (xy 337.82 203.2)
		)
		(stroke
			(width 0)
			(type default)
		)
	)
	(wire
		(pts
			(xy 316.23 123.19) (xy 323.85 123.19)
		)
		(stroke
			(width 0)
			(type default)
		)
	)
	(wire
		(pts
			(xy 271.78 113.03) (xy 280.67 113.03)
		)
		(stroke
			(width 0)
			(type default)
		)
	)
	(wire
		(pts
			(xy 341.63 96.52) (xy 341.63 97.79)
		)
		(stroke
			(width 0)
			(type default)
		)
	)
	(wire
		(pts
			(xy 316.23 179.07) (xy 330.2 179.07)
		)
		(stroke
			(width 0)
			(type default)
		)
	)
	(bus
		(pts
			(xy 331.47 182.88) (xy 331.47 185.42)
		)
		(stroke
			(width 0)
			(type default)
		)
	)
	(wire
		(pts
			(xy 316.23 189.23) (xy 330.2 189.23)
		)
		(stroke
			(width 0)
			(type default)
		)
	)
	(wire
		(pts
			(xy 316.23 191.77) (xy 330.2 191.77)
		)
		(stroke
			(width 0)
			(type default)
		)
	)
	(wire
		(pts
			(xy 97.79 125.73) (xy 97.79 127)
		)
		(stroke
			(width 0)
			(type default)
		)
	)
	(bus
		(pts
			(xy 271.78 170.18) (xy 271.78 172.72)
		)
		(stroke
			(width 0)
			(type default)
		)
	)
	(wire
		(pts
			(xy 214.63 107.95) (xy 214.63 109.22)
		)
		(stroke
			(width 0)
			(type default)
		)
	)
	(wire
		(pts
			(xy 77.47 187.96) (xy 77.47 189.23)
		)
		(stroke
			(width 0)
			(type default)
		)
	)
	(wire
		(pts
			(xy 214.63 115.57) (xy 214.63 114.3)
		)
		(stroke
			(width 0)
			(type default)
		)
	)
	(wire
		(pts
			(xy 361.95 118.11) (xy 353.06 118.11)
		)
		(stroke
			(width 0)
			(type default)
		)
	)
	(wire
		(pts
			(xy 74.93 99.06) (xy 86.36 99.06)
		)
		(stroke
			(width 0)
			(type default)
		)
	)
	(wire
		(pts
			(xy 91.44 177.8) (xy 91.44 182.88)
		)
		(stroke
			(width 0)
			(type default)
		)
	)
	(wire
		(pts
			(xy 316.23 194.31) (xy 330.2 194.31)
		)
		(stroke
			(width 0)
			(type default)
		)
	)
	(wire
		(pts
			(xy 85.09 189.23) (xy 85.09 187.96)
		)
		(stroke
			(width 0)
			(type default)
		)
	)
	(bus
		(pts
			(xy 331.47 139.7) (xy 331.47 142.24)
		)
		(stroke
			(width 0)
			(type default)
		)
	)
	(bus
		(pts
			(xy 271.78 165.1) (xy 271.78 167.64)
		)
		(stroke
			(width 0)
			(type default)
		)
	)
	(wire
		(pts
			(xy 326.39 96.52) (xy 341.63 96.52)
		)
		(stroke
			(width 0)
			(type default)
		)
	)
	(wire
		(pts
			(xy 232.41 123.19) (xy 232.41 121.92)
		)
		(stroke
			(width 0)
			(type default)
		)
	)
	(bus
		(pts
			(xy 331.47 195.58) (xy 331.47 198.12)
		)
		(stroke
			(width 0)
			(type default)
		)
	)
	(wire
		(pts
			(xy 353.06 125.73) (xy 353.06 124.46)
		)
		(stroke
			(width 0)
			(type default)
		)
	)
	(wire
		(pts
			(xy 271.78 135.89) (xy 280.67 135.89)
		)
		(stroke
			(width 0)
			(type default)
		)
	)
	(wire
		(pts
			(xy 107.95 104.14) (xy 134.62 104.14)
		)
		(stroke
			(width 0)
			(type default)
		)
	)
	(wire
		(pts
			(xy 278.13 186.69) (xy 280.67 186.69)
		)
		(stroke
			(width 0)
			(type default)
		)
	)
	(wire
		(pts
			(xy 223.52 116.84) (xy 223.52 115.57)
		)
		(stroke
			(width 0)
			(type default)
		)
	)
	(wire
		(pts
			(xy 370.84 118.11) (xy 370.84 116.84)
		)
		(stroke
			(width 0)
			(type default)
		)
	)
	(bus
		(pts
			(xy 332.74 165.1) (xy 337.82 165.1)
		)
		(stroke
			(width 0)
			(type default)
		)
	)
	(wire
		(pts
			(xy 223.52 123.19) (xy 223.52 121.92)
		)
		(stroke
			(width 0)
			(type default)
		)
	)
	(wire
		(pts
			(xy 316.23 184.15) (xy 330.2 184.15)
		)
		(stroke
			(width 0)
			(type default)
		)
	)
	(bus
		(pts
			(xy 270.51 185.42) (xy 264.16 185.42)
		)
		(stroke
			(width 0)
			(type default)
		)
	)
	(wire
		(pts
			(xy 242.57 96.52) (xy 251.46 96.52)
		)
		(stroke
			(width 0)
			(type default)
		)
	)
	(bus
		(pts
			(xy 331.47 177.8) (xy 331.47 180.34)
		)
		(stroke
			(width 0)
			(type default)
		)
	)
	(bus
		(pts
			(xy 331.47 190.5) (xy 331.47 193.04)
		)
		(stroke
			(width 0)
			(type default)
		)
	)
	(wire
		(pts
			(xy 279.4 200.66) (xy 279.4 199.39)
		)
		(stroke
			(width 0)
			(type default)
		)
	)
	(bus
		(pts
			(xy 271.78 180.34) (xy 271.78 182.88)
		)
		(stroke
			(width 0)
			(type default)
		)
	)
	(wire
		(pts
			(xy 316.23 138.43) (xy 330.2 138.43)
		)
		(stroke
			(width 0)
			(type default)
		)
	)
	(wire
		(pts
			(xy 91.44 170.18) (xy 91.44 172.72)
		)
		(stroke
			(width 0)
			(type default)
		)
	)
	(wire
		(pts
			(xy 261.62 97.79) (xy 261.62 96.52)
		)
		(stroke
			(width 0)
			(type default)
		)
	)
	(wire
		(pts
			(xy 361.95 125.73) (xy 361.95 124.46)
		)
		(stroke
			(width 0)
			(type default)
		)
	)
	(wire
		(pts
			(xy 124.46 121.92) (xy 124.46 127)
		)
		(stroke
			(width 0)
			(type default)
		)
	)
	(wire
		(pts
			(xy 271.78 96.52) (xy 271.78 113.03)
		)
		(stroke
			(width 0)
			(type default)
		)
	)
	(wire
		(pts
			(xy 232.41 104.14) (xy 232.41 102.87)
		)
		(stroke
			(width 0)
			(type default)
		)
	)
	(wire
		(pts
			(xy 261.62 96.52) (xy 271.78 96.52)
		)
		(stroke
			(width 0)
			(type default)
		)
	)
	(wire
		(pts
			(xy 351.79 96.52) (xy 341.63 96.52)
		)
		(stroke
			(width 0)
			(type default)
		)
	)
	(bus
		(pts
			(xy 331.47 185.42) (xy 331.47 187.96)
		)
		(stroke
			(width 0)
			(type default)
		)
	)
	(wire
		(pts
			(xy 232.41 96.52) (xy 242.57 96.52)
		)
		(stroke
			(width 0)
			(type default)
		)
	)
	(wire
		(pts
			(xy 316.23 125.73) (xy 323.85 125.73)
		)
		(stroke
			(width 0)
			(type default)
		)
	)
	(wire
		(pts
			(xy 119.38 111.76) (xy 134.62 111.76)
		)
		(stroke
			(width 0)
			(type default)
		)
	)
	(wire
		(pts
			(xy 236.22 194.31) (xy 236.22 195.58)
		)
		(stroke
			(width 0)
			(type default)
		)
	)
	(wire
		(pts
			(xy 265.43 207.01) (xy 265.43 205.74)
		)
		(stroke
			(width 0)
			(type default)
		)
	)
	(wire
		(pts
			(xy 91.44 187.96) (xy 91.44 189.23)
		)
		(stroke
			(width 0)
			(type default)
		)
	)
	(wire
		(pts
			(xy 124.46 121.92) (xy 134.62 121.92)
		)
		(stroke
			(width 0)
			(type default)
		)
	)
	(wire
		(pts
			(xy 326.39 105.41) (xy 326.39 96.52)
		)
		(stroke
			(width 0)
			(type default)
		)
	)
	(wire
		(pts
			(xy 273.05 161.29) (xy 280.67 161.29)
		)
		(stroke
			(width 0)
			(type default)
		)
	)
	(wire
		(pts
			(xy 66.04 106.68) (xy 69.85 106.68)
		)
		(stroke
			(width 0)
			(type default)
		)
	)
	(wire
		(pts
			(xy 265.43 200.66) (xy 265.43 196.85)
		)
		(stroke
			(width 0)
			(type default)
		)
	)
	(bus
		(pts
			(xy 271.78 167.64) (xy 271.78 170.18)
		)
		(stroke
			(width 0)
			(type default)
		)
	)
	(wire
		(pts
			(xy 162.56 193.04) (xy 162.56 191.77)
		)
		(stroke
			(width 0)
			(type default)
		)
	)
	(bus
		(pts
			(xy 331.47 147.32) (xy 331.47 149.86)
		)
		(stroke
			(width 0)
			(type default)
		)
	)
	(wire
		(pts
			(xy 223.52 115.57) (xy 232.41 115.57)
		)
		(stroke
			(width 0)
			(type default)
		)
	)
	(wire
		(pts
			(xy 370.84 88.9) (xy 370.84 90.17)
		)
		(stroke
			(width 0)
			(type default)
		)
	)
	(wire
		(pts
			(xy 370.84 109.22) (xy 370.84 111.76)
		)
		(stroke
			(width 0)
			(type default)
		)
	)
	(bus
		(pts
			(xy 331.47 152.4) (xy 331.47 154.94)
		)
		(stroke
			(width 0)
			(type default)
		)
	)
	(wire
		(pts
			(xy 63.5 111.76) (xy 81.28 111.76)
		)
		(stroke
			(width 0)
			(type default)
		)
	)
	(wire
		(pts
			(xy 74.93 121.92) (xy 86.36 121.92)
		)
		(stroke
			(width 0)
			(type default)
		)
	)
	(bus
		(pts
			(xy 331.47 198.12) (xy 331.47 200.66)
		)
		(stroke
			(width 0)
			(type default)
		)
	)
	(wire
		(pts
			(xy 232.41 116.84) (xy 232.41 115.57)
		)
		(stroke
			(width 0)
			(type default)
		)
	)
	(wire
		(pts
			(xy 91.44 121.92) (xy 124.46 121.92)
		)
		(stroke
			(width 0)
			(type default)
		)
	)
	(wire
		(pts
			(xy 105.41 106.68) (xy 105.41 127)
		)
		(stroke
			(width 0)
			(type default)
		)
	)
	(wire
		(pts
			(xy 251.46 104.14) (xy 251.46 102.87)
		)
		(stroke
			(width 0)
			(type default)
		)
	)
	(wire
		(pts
			(xy 242.57 116.84) (xy 242.57 115.57)
		)
		(stroke
			(width 0)
			(type default)
		)
	)
	(wire
		(pts
			(xy 223.52 104.14) (xy 223.52 102.87)
		)
		(stroke
			(width 0)
			(type default)
		)
	)
	(wire
		(pts
			(xy 66.04 121.92) (xy 69.85 121.92)
		)
		(stroke
			(width 0)
			(type default)
		)
	)
	(wire
		(pts
			(xy 86.36 104.14) (xy 107.95 104.14)
		)
		(stroke
			(width 0)
			(type default)
		)
	)
	(wire
		(pts
			(xy 271.78 128.27) (xy 280.67 128.27)
		)
		(stroke
			(width 0)
			(type default)
		)
	)
	(bus
		(pts
			(xy 331.47 149.86) (xy 331.47 152.4)
		)
		(stroke
			(width 0)
			(type default)
		)
	)
	(wire
		(pts
			(xy 265.43 196.85) (xy 280.67 196.85)
		)
		(stroke
			(width 0)
			(type default)
		)
	)
	(wire
		(pts
			(xy 66.04 99.06) (xy 69.85 99.06)
		)
		(stroke
			(width 0)
			(type default)
		)
	)
	(wire
		(pts
			(xy 100.33 96.52) (xy 134.62 96.52)
		)
		(stroke
			(width 0)
			(type default)
		)
	)
	(wire
		(pts
			(xy 243.84 201.93) (xy 243.84 200.66)
		)
		(stroke
			(width 0)
			(type default)
		)
	)
	(wire
		(pts
			(xy 316.23 143.51) (xy 330.2 143.51)
		)
		(stroke
			(width 0)
			(type default)
		)
	)
	(wire
		(pts
			(xy 320.04 96.52) (xy 320.04 113.03)
		)
		(stroke
			(width 0)
			(type default)
		)
	)
	(wire
		(pts
			(xy 113.03 129.54) (xy 113.03 125.73)
		)
		(stroke
			(width 0)
			(type default)
		)
	)
	(wire
		(pts
			(xy 127 119.38) (xy 127 127)
		)
		(stroke
			(width 0)
			(type default)
		)
	)
	(wire
		(pts
			(xy 251.46 123.19) (xy 251.46 121.92)
		)
		(stroke
			(width 0)
			(type default)
		)
	)
	(wire
		(pts
			(xy 162.56 171.45) (xy 162.56 177.8)
		)
		(stroke
			(width 0)
			(type default)
		)
	)
	(wire
		(pts
			(xy 361.95 119.38) (xy 361.95 118.11)
		)
		(stroke
			(width 0)
			(type default)
		)
	)
	(wire
		(pts
			(xy 242.57 104.14) (xy 242.57 102.87)
		)
		(stroke
			(width 0)
			(type default)
		)
	)
	(wire
		(pts
			(xy 251.46 115.57) (xy 261.62 115.57)
		)
		(stroke
			(width 0)
			(type default)
		)
	)
	(wire
		(pts
			(xy 251.46 96.52) (xy 261.62 96.52)
		)
		(stroke
			(width 0)
			(type default)
		)
	)
	(wire
		(pts
			(xy 116.84 125.73) (xy 116.84 127)
		)
		(stroke
			(width 0)
			(type default)
		)
	)
	(wire
		(pts
			(xy 91.44 99.06) (xy 102.87 99.06)
		)
		(stroke
			(width 0)
			(type default)
		)
	)
	(wire
		(pts
			(xy 318.77 96.52) (xy 320.04 96.52)
		)
		(stroke
			(width 0)
			(type default)
		)
	)
	(polyline
		(pts
			(xy 100.33 213.995) (xy 100.33 146.05)
		)
		(stroke
			(width 0)
			(type dash)
		)
	)
	(wire
		(pts
			(xy 121.92 185.42) (xy 129.54 185.42)
		)
		(stroke
			(width 0)
			(type default)
		)
	)
	(wire
		(pts
			(xy 105.41 106.68) (xy 134.62 106.68)
		)
		(stroke
			(width 0)
			(type default)
		)
	)
	(wire
		(pts
			(xy 242.57 115.57) (xy 251.46 115.57)
		)
		(stroke
			(width 0)
			(type default)
		)
	)
	(wire
		(pts
			(xy 261.62 123.19) (xy 261.62 121.92)
		)
		(stroke
			(width 0)
			(type default)
		)
	)
	(wire
		(pts
			(xy 242.57 97.79) (xy 242.57 96.52)
		)
		(stroke
			(width 0)
			(type default)
		)
	)
	(bus
		(pts
			(xy 331.47 163.83) (xy 332.74 165.1)
		)
		(stroke
			(width 0)
			(type default)
		)
	)
	(wire
		(pts
			(xy 316.23 151.13) (xy 330.2 151.13)
		)
		(stroke
			(width 0)
			(type default)
		)
	)
	(wire
		(pts
			(xy 316.23 146.05) (xy 330.2 146.05)
		)
		(stroke
			(width 0)
			(type default)
		)
	)
	(wire
		(pts
			(xy 93.98 129.54) (xy 93.98 125.73)
		)
		(stroke
			(width 0)
			(type default)
		)
	)
	(wire
		(pts
			(xy 273.05 176.53) (xy 280.67 176.53)
		)
		(stroke
			(width 0)
			(type default)
		)
	)
	(wire
		(pts
			(xy 236.22 194.31) (xy 243.84 194.31)
		)
		(stroke
			(width 0)
			(type default)
		)
	)
	(wire
		(pts
			(xy 214.63 115.57) (xy 223.52 115.57)
		)
		(stroke
			(width 0)
			(type default)
		)
	)
	(wire
		(pts
			(xy 232.41 115.57) (xy 242.57 115.57)
		)
		(stroke
			(width 0)
			(type default)
		)
	)
	(wire
		(pts
			(xy 227.33 201.93) (xy 227.33 200.66)
		)
		(stroke
			(width 0)
			(type default)
		)
	)
	(wire
		(pts
			(xy 271.78 140.97) (xy 280.67 140.97)
		)
		(stroke
			(width 0)
			(type default)
		)
	)
	(wire
		(pts
			(xy 119.38 111.76) (xy 119.38 127)
		)
		(stroke
			(width 0)
			(type default)
		)
	)
	(bus
		(pts
			(xy 331.47 154.94) (xy 331.47 157.48)
		)
		(stroke
			(width 0)
			(type default)
		)
	)
	(bus
		(pts
			(xy 271.78 182.88) (xy 271.78 184.15)
		)
		(stroke
			(width 0)
			(type default)
		)
	)
	(wire
		(pts
			(xy 273.05 158.75) (xy 280.67 158.75)
		)
		(stroke
			(width 0)
			(type default)
		)
	)
	(wire
		(pts
			(xy 316.23 181.61) (xy 330.2 181.61)
		)
		(stroke
			(width 0)
			(type default)
		)
	)
	(wire
		(pts
			(xy 271.78 143.51) (xy 280.67 143.51)
		)
		(stroke
			(width 0)
			(type default)
		)
	)
	(wire
		(pts
			(xy 162.56 185.42) (xy 170.18 185.42)
		)
		(stroke
			(width 0)
			(type default)
		)
	)
	(wire
		(pts
			(xy 107.95 104.14) (xy 107.95 127)
		)
		(stroke
			(width 0)
			(type default)
		)
	)
	(wire
		(pts
			(xy 66.04 114.3) (xy 69.85 114.3)
		)
		(stroke
			(width 0)
			(type default)
		)
	)
	(wire
		(pts
			(xy 273.05 171.45) (xy 280.67 171.45)
		)
		(stroke
			(width 0)
			(type default)
		)
	)
	(wire
		(pts
			(xy 162.56 185.42) (xy 162.56 186.69)
		)
		(stroke
			(width 0)
			(type default)
		)
	)
	(wire
		(pts
			(xy 316.23 156.21) (xy 330.2 156.21)
		)
		(stroke
			(width 0)
			(type default)
		)
	)
	(wire
		(pts
			(xy 316.23 148.59) (xy 330.2 148.59)
		)
		(stroke
			(width 0)
			(type default)
		)
	)
	(wire
		(pts
			(xy 121.92 185.42) (xy 121.92 186.69)
		)
		(stroke
			(width 0)
			(type default)
		)
	)
	(wire
		(pts
			(xy 77.47 189.23) (xy 85.09 189.23)
		)
		(stroke
			(width 0)
			(type default)
		)
	)
	(wire
		(pts
			(xy 316.23 196.85) (xy 330.2 196.85)
		)
		(stroke
			(width 0)
			(type default)
		)
	)
	(wire
		(pts
			(xy 261.62 116.84) (xy 261.62 115.57)
		)
		(stroke
			(width 0)
			(type default)
		)
	)
	(wire
		(pts
			(xy 63.5 104.14) (xy 81.28 104.14)
		)
		(stroke
			(width 0)
			(type default)
		)
	)
	(wire
		(pts
			(xy 77.47 170.18) (xy 77.47 182.88)
		)
		(stroke
			(width 0)
			(type default)
		)
	)
	(bus
		(pts
			(xy 331.47 180.34) (xy 331.47 182.88)
		)
		(stroke
			(width 0)
			(type default)
		)
	)
	(wire
		(pts
			(xy 91.44 114.3) (xy 121.92 114.3)
		)
		(stroke
			(width 0)
			(type default)
		)
	)
	(wire
		(pts
			(xy 162.56 182.88) (xy 162.56 185.42)
		)
		(stroke
			(width 0)
			(type default)
		)
	)
	(wire
		(pts
			(xy 251.46 97.79) (xy 251.46 96.52)
		)
		(stroke
			(width 0)
			(type default)
		)
	)
	(wire
		(pts
			(xy 271.78 151.13) (xy 280.67 151.13)
		)
		(stroke
			(width 0)
			(type default)
		)
	)
	(wire
		(pts
			(xy 316.23 158.75) (xy 330.2 158.75)
		)
		(stroke
			(width 0)
			(type default)
		)
	)
	(bus
		(pts
			(xy 331.47 162.56) (xy 331.47 163.83)
		)
		(stroke
			(width 0)
			(type default)
		)
	)
	(wire
		(pts
			(xy 342.9 125.73) (xy 342.9 124.46)
		)
		(stroke
			(width 0)
			(type default)
		)
	)
	(wire
		(pts
			(xy 370.84 118.11) (xy 361.95 118.11)
		)
		(stroke
			(width 0)
			(type default)
		)
	)
	(wire
		(pts
			(xy 85.09 189.23) (xy 91.44 189.23)
		)
		(stroke
			(width 0)
			(type default)
		)
	)
	(polyline
		(pts
			(xy 12.065 70.485) (xy 187.96 70.485)
		)
		(stroke
			(width 0)
			(type dash)
		)
	)
	(wire
		(pts
			(xy 251.46 116.84) (xy 251.46 115.57)
		)
		(stroke
			(width 0)
			(type default)
		)
	)
	(bus
		(pts
			(xy 271.78 172.72) (xy 271.78 175.26)
		)
		(stroke
			(width 0)
			(type default)
		)
	)
	(wire
		(pts
			(xy 214.63 95.25) (xy 214.63 96.52)
		)
		(stroke
			(width 0)
			(type default)
		)
	)
	(wire
		(pts
			(xy 102.87 99.06) (xy 134.62 99.06)
		)
		(stroke
			(width 0)
			(type default)
		)
	)
	(wire
		(pts
			(xy 121.92 193.04) (xy 121.92 191.77)
		)
		(stroke
			(width 0)
			(type default)
		)
	)
	(wire
		(pts
			(xy 279.4 199.39) (xy 280.67 199.39)
		)
		(stroke
			(width 0)
			(type default)
		)
	)
	(wire
		(pts
			(xy 273.05 179.07) (xy 280.67 179.07)
		)
		(stroke
			(width 0)
			(type default)
		)
	)
	(wire
		(pts
			(xy 273.05 168.91) (xy 280.67 168.91)
		)
		(stroke
			(width 0)
			(type default)
		)
	)
	(wire
		(pts
			(xy 86.36 96.52) (xy 100.33 96.52)
		)
		(stroke
			(width 0)
			(type default)
		)
	)
	(wire
		(pts
			(xy 273.05 181.61) (xy 280.67 181.61)
		)
		(stroke
			(width 0)
			(type default)
		)
	)
	(wire
		(pts
			(xy 316.23 140.97) (xy 330.2 140.97)
		)
		(stroke
			(width 0)
			(type default)
		)
	)
	(wire
		(pts
			(xy 74.93 106.68) (xy 86.36 106.68)
		)
		(stroke
			(width 0)
			(type default)
		)
	)
	(wire
		(pts
			(xy 121.92 114.3) (xy 121.92 127)
		)
		(stroke
			(width 0)
			(type default)
		)
	)
	(wire
		(pts
			(xy 214.63 88.9) (xy 214.63 90.17)
		)
		(stroke
			(width 0)
			(type default)
		)
	)
	(wire
		(pts
			(xy 121.92 182.88) (xy 121.92 185.42)
		)
		(stroke
			(width 0)
			(type default)
		)
	)
	(wire
		(pts
			(xy 316.23 186.69) (xy 330.2 186.69)
		)
		(stroke
			(width 0)
			(type default)
		)
	)
	(wire
		(pts
			(xy 100.33 96.52) (xy 100.33 127)
		)
		(stroke
			(width 0)
			(type default)
		)
	)
	(wire
		(pts
			(xy 341.63 104.14) (xy 341.63 102.87)
		)
		(stroke
			(width 0)
			(type default)
		)
	)
	(wire
		(pts
			(xy 88.9 182.88) (xy 91.44 182.88)
		)
		(stroke
			(width 0)
			(type default)
		)
	)
	(polyline
		(pts
			(xy 187.96 213.995) (xy 187.96 146.05)
		)
		(stroke
			(width 0)
			(type dash)
		)
	)
	(wire
		(pts
			(xy 360.68 96.52) (xy 351.79 96.52)
		)
		(stroke
			(width 0)
			(type default)
		)
	)
	(wire
		(pts
			(xy 320.04 96.52) (xy 326.39 96.52)
		)
		(stroke
			(width 0)
			(type default)
		)
	)
	(bus
		(pts
			(xy 331.47 144.78) (xy 331.47 147.32)
		)
		(stroke
			(width 0)
			(type default)
		)
	)
	(wire
		(pts
			(xy 360.68 97.79) (xy 360.68 96.52)
		)
		(stroke
			(width 0)
			(type default)
		)
	)
	(wire
		(pts
			(xy 243.84 194.31) (xy 243.84 195.58)
		)
		(stroke
			(width 0)
			(type default)
		)
	)
	(wire
		(pts
			(xy 74.93 114.3) (xy 86.36 114.3)
		)
		(stroke
			(width 0)
			(type default)
		)
	)
	(wire
		(pts
			(xy 242.57 123.19) (xy 242.57 121.92)
		)
		(stroke
			(width 0)
			(type default)
		)
	)
	(wire
		(pts
			(xy 252.73 194.31) (xy 252.73 195.58)
		)
		(stroke
			(width 0)
			(type default)
		)
	)
	(wire
		(pts
			(xy 86.36 111.76) (xy 119.38 111.76)
		)
		(stroke
			(width 0)
			(type default)
		)
	)
	(wire
		(pts
			(xy 360.68 104.14) (xy 360.68 102.87)
		)
		(stroke
			(width 0)
			(type default)
		)
	)
	(wire
		(pts
			(xy 273.05 163.83) (xy 280.67 163.83)
		)
		(stroke
			(width 0)
			(type default)
		)
	)
	(label "VTERM"
		(at 335.28 118.11 0)
		(effects
			(font
				(size 1.27 1.27)
			)
			(justify left bottom)
		)
	)
	(label "CFG1"
		(at 273.05 176.53 0)
		(effects
			(font
				(size 1.27 1.27)
			)
			(justify left bottom)
		)
	)
	(label "SIOB_N"
		(at 271.78 135.89 0)
		(effects
			(font
				(size 1.27 1.27)
			)
			(justify left bottom)
		)
	)
	(label "CSI0.CLK_P"
		(at 318.77 158.75 0)
		(effects
			(font
				(size 1.27 1.27)
			)
			(justify left bottom)
		)
	)
	(label "XRES"
		(at 270.51 196.85 0)
		(effects
			(font
				(size 1.27 1.27)
			)
			(justify left bottom)
		)
	)
	(label "VDDIO"
		(at 121.92 171.45 270)
		(effects
			(font
				(size 1.27 1.27)
			)
			(justify right bottom)
		)
	)
	(label "MFP0"
		(at 273.05 161.29 0)
		(effects
			(font
				(size 1.27 1.27)
			)
			(justify left bottom)
		)
	)
	(label "CSI0.D3_N"
		(at 318.77 156.21 0)
		(effects
			(font
				(size 1.27 1.27)
			)
			(justify left bottom)
		)
	)
	(label "CSI1.D3_N"
		(at 318.77 194.31 0)
		(effects
			(font
				(size 1.27 1.27)
			)
			(justify left bottom)
		)
	)
	(label "MFP7"
		(at 273.05 179.07 0)
		(effects
			(font
				(size 1.27 1.27)
			)
			(justify left bottom)
		)
	)
	(label "SIOB_N"
		(at 134.62 106.68 180)
		(effects
			(font
				(size 1.27 1.27)
			)
			(justify right bottom)
		)
	)
	(label "CAP_VDD"
		(at 252.73 194.31 0)
		(effects
			(font
				(size 1.27 1.27)
			)
			(justify left bottom)
		)
	)
	(label "SIOC_P"
		(at 271.78 140.97 0)
		(effects
			(font
				(size 1.27 1.27)
			)
			(justify left bottom)
		)
	)
	(label "SIOB_P"
		(at 271.78 133.35 0)
		(effects
			(font
				(size 1.27 1.27)
			)
			(justify left bottom)
		)
	)
	(label "SIOA_N"
		(at 271.78 128.27 0)
		(effects
			(font
				(size 1.27 1.27)
			)
			(justify left bottom)
		)
	)
	(label "CSI1.CLK_N"
		(at 318.77 199.39 0)
		(effects
			(font
				(size 1.27 1.27)
			)
			(justify left bottom)
		)
	)
	(label "CSI1.D0_N"
		(at 318.77 179.07 0)
		(effects
			(font
				(size 1.27 1.27)
			)
			(justify left bottom)
		)
	)
	(label "VDD"
		(at 264.16 115.57 0)
		(effects
			(font
				(size 1.27 1.27)
			)
			(justify left bottom)
		)
	)
	(label "SIOC_N"
		(at 271.78 143.51 0)
		(effects
			(font
				(size 1.27 1.27)
			)
			(justify left bottom)
		)
	)
	(label "SIOD_N"
		(at 134.62 121.92 180)
		(effects
			(font
				(size 1.27 1.27)
			)
			(justify right bottom)
		)
	)
	(label "MFP1"
		(at 273.05 163.83 0)
		(effects
			(font
				(size 1.27 1.27)
			)
			(justify left bottom)
		)
	)
	(label "SIOD_P"
		(at 271.78 148.59 0)
		(effects
			(font
				(size 1.27 1.27)
			)
			(justify left bottom)
		)
	)
	(label "CSI1.D0_P"
		(at 318.77 176.53 0)
		(effects
			(font
				(size 1.27 1.27)
			)
			(justify left bottom)
		)
	)
	(label "MFP4"
		(at 273.05 171.45 0)
		(effects
			(font
				(size 1.27 1.27)
			)
			(justify left bottom)
		)
	)
	(label "MFP5"
		(at 273.05 173.99 0)
		(effects
			(font
				(size 1.27 1.27)
			)
			(justify left bottom)
		)
	)
	(label "X1"
		(at 278.13 186.69 0)
		(effects
			(font
				(size 1.27 1.27)
			)
			(justify left bottom)
		)
	)
	(label "CFG0"
		(at 273.05 158.75 0)
		(effects
			(font
				(size 1.27 1.27)
			)
			(justify left bottom)
		)
	)
	(label "X1"
		(at 77.47 170.18 270)
		(effects
			(font
				(size 1.27 1.27)
			)
			(justify right bottom)
		)
	)
	(label "SIOB_P"
		(at 134.62 104.14 180)
		(effects
			(font
				(size 1.27 1.27)
			)
			(justify right bottom)
		)
	)
	(label "X2"
		(at 91.44 170.18 270)
		(effects
			(font
				(size 1.27 1.27)
			)
			(justify right bottom)
		)
	)
	(label "SIOA_N"
		(at 134.62 99.06 180)
		(effects
			(font
				(size 1.27 1.27)
			)
			(justify right bottom)
		)
	)
	(label "CSI1.D1_P"
		(at 318.77 181.61 0)
		(effects
			(font
				(size 1.27 1.27)
			)
			(justify left bottom)
		)
	)
	(label "VDD_1.8V"
		(at 262.89 96.52 0)
		(effects
			(font
				(size 1.27 1.27)
			)
			(justify left bottom)
		)
	)
	(label "SIOA_P"
		(at 134.62 96.52 180)
		(effects
			(font
				(size 1.27 1.27)
			)
			(justify right bottom)
		)
	)
	(label "SIOD_N"
		(at 271.78 151.13 0)
		(effects
			(font
				(size 1.27 1.27)
			)
			(justify left bottom)
		)
	)
	(label "CSI0.D2_P"
		(at 318.77 148.59 0)
		(effects
			(font
				(size 1.27 1.27)
			)
			(justify left bottom)
		)
	)
	(label "CFG1"
		(at 170.18 185.42 180)
		(effects
			(font
				(size 1.27 1.27)
			)
			(justify right bottom)
		)
	)
	(label "PWDNB"
		(at 318.77 115.57 0)
		(effects
			(font
				(size 1.27 1.27)
			)
			(justify left bottom)
		)
	)
	(label "SIOA_P"
		(at 271.78 125.73 0)
		(effects
			(font
				(size 1.27 1.27)
			)
			(justify left bottom)
		)
	)
	(label "CSI0.D1_N"
		(at 318.77 146.05 0)
		(effects
			(font
				(size 1.27 1.27)
			)
			(justify left bottom)
		)
	)
	(label "CSI1.CLK_P"
		(at 318.77 196.85 0)
		(effects
			(font
				(size 1.27 1.27)
			)
			(justify left bottom)
		)
	)
	(label "CSI0.CLK_N"
		(at 318.77 161.29 0)
		(effects
			(font
				(size 1.27 1.27)
			)
			(justify left bottom)
		)
	)
	(label "CSI0.D3_P"
		(at 318.77 153.67 0)
		(effects
			(font
				(size 1.27 1.27)
			)
			(justify left bottom)
		)
	)
	(label "X2_R"
		(at 91.44 182.88 90)
		(effects
			(font
				(size 1.27 1.27)
			)
			(justify left bottom)
		)
	)
	(label "SIOC_N"
		(at 134.62 114.3 180)
		(effects
			(font
				(size 1.27 1.27)
			)
			(justify right bottom)
		)
	)
	(label "CSI1.D1_N"
		(at 318.77 184.15 0)
		(effects
			(font
				(size 1.27 1.27)
			)
			(justify left bottom)
		)
	)
	(label "CSI0.D0_N"
		(at 318.77 140.97 0)
		(effects
			(font
				(size 1.27 1.27)
			)
			(justify left bottom)
		)
	)
	(label "CSI1.D3_P"
		(at 318.77 191.77 0)
		(effects
			(font
				(size 1.27 1.27)
			)
			(justify left bottom)
		)
	)
	(label "CSI0.D2_N"
		(at 318.77 151.13 0)
		(effects
			(font
				(size 1.27 1.27)
			)
			(justify left bottom)
		)
	)
	(label "MFP2"
		(at 273.05 166.37 0)
		(effects
			(font
				(size 1.27 1.27)
			)
			(justify left bottom)
		)
	)
	(label "CSI1.D2_P"
		(at 318.77 186.69 0)
		(effects
			(font
				(size 1.27 1.27)
			)
			(justify left bottom)
		)
	)
	(label "CSI0.D0_P"
		(at 318.77 138.43 0)
		(effects
			(font
				(size 1.27 1.27)
			)
			(justify left bottom)
		)
	)
	(label "X2"
		(at 278.13 189.23 0)
		(effects
			(font
				(size 1.27 1.27)
			)
			(justify left bottom)
		)
	)
	(label "MFP8"
		(at 273.05 181.61 0)
		(effects
			(font
				(size 1.27 1.27)
			)
			(justify left bottom)
		)
	)
	(label "CSI0.D1_P"
		(at 318.77 143.51 0)
		(effects
			(font
				(size 1.27 1.27)
			)
			(justify left bottom)
		)
	)
	(label "VDDIO"
		(at 162.56 171.45 270)
		(effects
			(font
				(size 1.27 1.27)
			)
			(justify right bottom)
		)
	)
	(label "MFP3"
		(at 273.05 168.91 0)
		(effects
			(font
				(size 1.27 1.27)
			)
			(justify left bottom)
		)
	)
	(label "CFG0"
		(at 129.54 185.42 180)
		(effects
			(font
				(size 1.27 1.27)
			)
			(justify right bottom)
		)
	)
	(label "SIOC_P"
		(at 134.62 111.76 180)
		(effects
			(font
				(size 1.27 1.27)
			)
			(justify right bottom)
		)
	)
	(label "SIOD_P"
		(at 134.62 119.38 180)
		(effects
			(font
				(size 1.27 1.27)
			)
			(justify right bottom)
		)
	)
	(label "CSI1.D2_N"
		(at 318.77 189.23 0)
		(effects
			(font
				(size 1.27 1.27)
			)
			(justify left bottom)
		)
	)
	(global_label "VDDIO"
		(shape output)
		(at 318.77 96.52 180)
		(fields_autoplaced yes)
		(effects
			(font
				(size 1.27 1.27)
			)
			(justify right)
		)
		(property "Intersheetrefs" "${INTERSHEET_REFS}"
			(at 310.2209 96.52 0)
			(effects
				(font
					(size 1.27 1.27)
				)
				(justify right)
				(hide yes)
			)
		)
	)
	(hierarchical_label "MFP[0..8]"
		(shape bidirectional)
		(at 264.16 185.42 180)
		(effects
			(font
				(size 1.27 1.27)
			)
			(justify right)
		)
	)
	(hierarchical_label "SIOCP"
		(shape bidirectional)
		(at 63.5 111.76 180)
		(effects
			(font
				(size 1.27 1.27)
			)
			(justify right)
		)
	)
	(hierarchical_label "CSI0{CSI}"
		(shape output)
		(at 337.82 165.1 0)
		(effects
			(font
				(size 1.27 1.27)
			)
			(justify left)
		)
	)
	(hierarchical_label "CSI1{CSI}"
		(shape output)
		(at 337.82 203.2 0)
		(effects
			(font
				(size 1.27 1.27)
			)
			(justify left)
		)
	)
	(hierarchical_label "SDA"
		(shape bidirectional)
		(at 323.85 125.73 0)
		(effects
			(font
				(size 1.27 1.27)
			)
			(justify left)
		)
	)
	(hierarchical_label "SIOAP"
		(shape bidirectional)
		(at 63.5 96.52 180)
		(effects
			(font
				(size 1.27 1.27)
			)
			(justify right)
		)
	)
	(hierarchical_label "SIODP"
		(shape bidirectional)
		(at 63.5 119.38 180)
		(effects
			(font
				(size 1.27 1.27)
			)
			(justify right)
		)
	)
	(hierarchical_label "SCL"
		(shape input)
		(at 323.85 123.19 0)
		(effects
			(font
				(size 1.27 1.27)
			)
			(justify left)
		)
	)
	(hierarchical_label "SIOBP"
		(shape bidirectional)
		(at 63.5 104.14 180)
		(effects
			(font
				(size 1.27 1.27)
			)
			(justify right)
		)
	)
	(symbol
		(lib_id "antmicropower:GND")
		(at 236.22 201.93 0)
		(unit 1)
		(exclude_from_sim no)
		(in_bom yes)
		(on_board yes)
		(dnp no)
		(property "Reference" "#PWR081"
			(at 245.11 204.47 0)
			(effects
				(font
					(size 1.27 1.27)
					(thickness 0.15)
				)
				(justify left bottom)
				(hide yes)
			)
		)
		(property "Value" "GND"
			(at 236.22 205.74 0)
			(effects
				(font
					(size 1.27 1.27)
					(thickness 0.15)
				)
			)
		)
		(property "Footprint" ""
			(at 245.11 209.55 0)
			(effects
				(font
					(size 1.27 1.27)
					(thickness 0.15)
				)
				(justify left bottom)
				(hide yes)
			)
		)
		(property "Datasheet" ""
			(at 245.11 214.63 0)
			(effects
				(font
					(size 1.27 1.27)
					(thickness 0.15)
				)
				(justify left bottom)
				(hide yes)
			)
		)
		(property "Description" ""
			(at 236.22 201.93 0)
			(effects
				(font
					(size 1.27 1.27)
				)
				(hide yes)
			)
		)
		(property "Author" "Antmicro"
			(at 245.11 209.55 0)
			(effects
				(font
					(size 1.27 1.27)
					(thickness 0.15)
				)
				(justify left bottom)
				(hide yes)
			)
		)
		(property "License" "Apache-2.0"
			(at 245.11 212.09 0)
			(effects
				(font
					(size 1.27 1.27)
					(thickness 0.15)
				)
				(justify left bottom)
				(hide yes)
			)
		)
		(pin "1"
		)
		(instances
			(project "gmsl-deserializer"
				(path ""
					(reference "#PWR081")
					(unit 1)
				)
			)
		)
	)
	(symbol
		(lib_id "antmicropower:GND")
		(at 261.62 123.19 0)
		(unit 1)
		(exclude_from_sim no)
		(in_bom yes)
		(on_board yes)
		(dnp no)
		(property "Reference" "#PWR089"
			(at 270.51 125.73 0)
			(effects
				(font
					(size 1.27 1.27)
					(thickness 0.15)
				)
				(justify left bottom)
				(hide yes)
			)
		)
		(property "Value" "GND"
			(at 261.62 127 0)
			(effects
				(font
					(size 1.27 1.27)
					(thickness 0.15)
				)
			)
		)
		(property "Footprint" ""
			(at 270.51 130.81 0)
			(effects
				(font
					(size 1.27 1.27)
					(thickness 0.15)
				)
				(justify left bottom)
				(hide yes)
			)
		)
		(property "Datasheet" ""
			(at 270.51 135.89 0)
			(effects
				(font
					(size 1.27 1.27)
					(thickness 0.15)
				)
				(justify left bottom)
				(hide yes)
			)
		)
		(property "Description" ""
			(at 261.62 123.19 0)
			(effects
				(font
					(size 1.27 1.27)
				)
				(hide yes)
			)
		)
		(property "Author" "Antmicro"
			(at 270.51 130.81 0)
			(effects
				(font
					(size 1.27 1.27)
					(thickness 0.15)
				)
				(justify left bottom)
				(hide yes)
			)
		)
		(property "License" "Apache-2.0"
			(at 270.51 133.35 0)
			(effects
				(font
					(size 1.27 1.27)
					(thickness 0.15)
				)
				(justify left bottom)
				(hide yes)
			)
		)
		(pin "1"
		)
		(instances
			(project "gmsl-deserializer"
				(path ""
					(reference "#PWR089")
					(unit 1)
				)
			)
		)
	)
	(symbol
		(lib_id "antmicroCapacitors0402:C_33p_0402")
		(at 77.47 187.96 90)
		(unit 1)
		(exclude_from_sim no)
		(in_bom yes)
		(on_board yes)
		(dnp no)
		(property "Reference" "C56"
			(at 71.755 184.15 90)
			(effects
				(font
					(size 1.27 1.27)
					(thickness 0.15)
				)
				(justify right)
			)
		)
		(property "Value" "C_33p_0402"
			(at 87.63 167.64 0)
			(effects
				(font
					(size 1.27 1.27)
					(thickness 0.15)
				)
				(justify left bottom)
				(hide yes)
			)
		)
		(property "Footprint" "antmicro-footprints:C_0402_1005Metric"
			(at 90.17 167.64 0)
			(effects
				(font
					(size 1.27 1.27)
					(thickness 0.15)
				)
				(justify left bottom)
				(hide yes)
			)
		)
		(property "Datasheet" "https://spicat.kyocera-avx.com/product/mlcc/chartview/04025A330FAT2A/"
			(at 92.71 167.64 0)
			(effects
				(font
					(size 1.27 1.27)
					(thickness 0.15)
				)
				(justify left bottom)
				(hide yes)
			)
		)
		(property "Description" "SMD Multilayer Ceramic Capacitor, 33 pF, 50 V, 0402 [1005 Metric], ± 5%, C0G / NP0, MC"
			(at 77.47 187.96 0)
			(effects
				(font
					(size 1.27 1.27)
				)
				(hide yes)
			)
		)
		(property "MPN" "04025A330FAT2A"
			(at 95.25 167.64 0)
			(effects
				(font
					(size 1.27 1.27)
					(thickness 0.15)
				)
				(justify left bottom)
				(hide yes)
			)
		)
		(property "Manufacturer" "KYOCERA AVX"
			(at 97.79 167.64 0)
			(effects
				(font
					(size 1.27 1.27)
					(thickness 0.15)
				)
				(justify left bottom)
				(hide yes)
			)
		)
		(property "License" "Apache-2.0"
			(at 100.33 167.64 0)
			(effects
				(font
					(size 1.27 1.27)
					(thickness 0.15)
				)
				(justify left bottom)
				(hide yes)
			)
		)
		(property "Author" "Antmicro"
			(at 102.87 167.64 0)
			(effects
				(font
					(size 1.27 1.27)
					(thickness 0.15)
				)
				(justify left bottom)
				(hide yes)
			)
		)
		(property "Val" "33p"
			(at 71.755 186.69 90)
			(effects
				(font
					(size 1.27 1.27)
					(thickness 0.15)
				)
				(justify right)
			)
		)
		(property "Voltage" ""
			(at 105.41 167.64 0)
			(effects
				(font
					(size 1.27 1.27)
				)
				(justify left bottom)
				(hide yes)
			)
		)
		(property "Dielectric" ""
			(at 107.95 167.64 0)
			(effects
				(font
					(size 1.27 1.27)
				)
				(justify left bottom)
				(hide yes)
			)
		)
		(pin "1"
		)
		(pin "2"
		)
		(instances
			(project "gmsl-deserializer"
				(path ""
					(reference "C56")
					(unit 1)
				)
			)
		)
	)
	(symbol
		(lib_id "antmicropower:+1V8")
		(at 214.63 88.9 0)
		(unit 1)
		(exclude_from_sim no)
		(in_bom yes)
		(on_board yes)
		(dnp no)
		(property "Reference" "#PWR074"
			(at 229.87 91.44 0)
			(effects
				(font
					(size 1.27 1.27)
					(thickness 0.15)
				)
				(justify left bottom)
				(hide yes)
			)
		)
		(property "Value" "+1V8"
			(at 214.63 85.09 0)
			(effects
				(font
					(size 1.27 1.27)
					(thickness 0.15)
				)
			)
		)
		(property "Footprint" ""
			(at 229.87 96.52 0)
			(effects
				(font
					(size 1.27 1.27)
					(thickness 0.15)
				)
				(justify left bottom)
				(hide yes)
			)
		)
		(property "Datasheet" ""
			(at 229.87 99.06 0)
			(effects
				(font
					(size 1.27 1.27)
					(thickness 0.15)
				)
				(justify left bottom)
				(hide yes)
			)
		)
		(property "Description" ""
			(at 214.63 88.9 0)
			(effects
				(font
					(size 1.27 1.27)
				)
				(hide yes)
			)
		)
		(property "Author" "Antmicro"
			(at 229.87 96.52 0)
			(effects
				(font
					(size 1.27 1.27)
					(thickness 0.15)
				)
				(justify left bottom)
				(hide yes)
			)
		)
		(property "License" "Apache-2.0"
			(at 229.87 99.06 0)
			(effects
				(font
					(size 1.27 1.27)
					(thickness 0.15)
				)
				(justify left bottom)
				(hide yes)
			)
		)
		(pin "1"
		)
		(instances
			(project "gmsl-deserializer"
				(path ""
					(reference "#PWR074")
					(unit 1)
				)
			)
		)
	)
	(symbol
		(lib_id "antmicropower:GND")
		(at 251.46 123.19 0)
		(unit 1)
		(exclude_from_sim no)
		(in_bom yes)
		(on_board yes)
		(dnp no)
		(property "Reference" "#PWR086"
			(at 260.35 125.73 0)
			(effects
				(font
					(size 1.27 1.27)
					(thickness 0.15)
				)
				(justify left bottom)
				(hide yes)
			)
		)
		(property "Value" "GND"
			(at 251.46 127 0)
			(effects
				(font
					(size 1.27 1.27)
					(thickness 0.15)
				)
			)
		)
		(property "Footprint" ""
			(at 260.35 130.81 0)
			(effects
				(font
					(size 1.27 1.27)
					(thickness 0.15)
				)
				(justify left bottom)
				(hide yes)
			)
		)
		(property "Datasheet" ""
			(at 260.35 135.89 0)
			(effects
				(font
					(size 1.27 1.27)
					(thickness 0.15)
				)
				(justify left bottom)
				(hide yes)
			)
		)
		(property "Description" ""
			(at 251.46 123.19 0)
			(effects
				(font
					(size 1.27 1.27)
				)
				(hide yes)
			)
		)
		(property "Author" "Antmicro"
			(at 260.35 130.81 0)
			(effects
				(font
					(size 1.27 1.27)
					(thickness 0.15)
				)
				(justify left bottom)
				(hide yes)
			)
		)
		(property "License" "Apache-2.0"
			(at 260.35 133.35 0)
			(effects
				(font
					(size 1.27 1.27)
					(thickness 0.15)
				)
				(justify left bottom)
				(hide yes)
			)
		)
		(pin "1"
		)
		(instances
			(project "gmsl-deserializer"
				(path ""
					(reference "#PWR086")
					(unit 1)
				)
			)
		)
	)
	(symbol
		(lib_id "antmicropower:GND")
		(at 93.98 129.54 0)
		(unit 1)
		(exclude_from_sim no)
		(in_bom yes)
		(on_board yes)
		(dnp no)
		(property "Reference" "#PWR070"
			(at 102.87 132.08 0)
			(effects
				(font
					(size 1.27 1.27)
					(thickness 0.15)
				)
				(justify left bottom)
				(hide yes)
			)
		)
		(property "Value" "GND"
			(at 93.98 133.35 0)
			(effects
				(font
					(size 1.27 1.27)
					(thickness 0.15)
				)
			)
		)
		(property "Footprint" ""
			(at 102.87 137.16 0)
			(effects
				(font
					(size 1.27 1.27)
					(thickness 0.15)
				)
				(justify left bottom)
				(hide yes)
			)
		)
		(property "Datasheet" ""
			(at 102.87 142.24 0)
			(effects
				(font
					(size 1.27 1.27)
					(thickness 0.15)
				)
				(justify left bottom)
				(hide yes)
			)
		)
		(property "Description" ""
			(at 93.98 129.54 0)
			(effects
				(font
					(size 1.27 1.27)
				)
				(hide yes)
			)
		)
		(property "Author" "Antmicro"
			(at 102.87 137.16 0)
			(effects
				(font
					(size 1.27 1.27)
					(thickness 0.15)
				)
				(justify left bottom)
				(hide yes)
			)
		)
		(property "License" "Apache-2.0"
			(at 102.87 139.7 0)
			(effects
				(font
					(size 1.27 1.27)
					(thickness 0.15)
				)
				(justify left bottom)
				(hide yes)
			)
		)
		(pin "1"
		)
		(instances
			(project "gmsl-deserializer"
				(path ""
					(reference "#PWR070")
					(unit 1)
				)
			)
		)
	)
	(symbol
		(lib_id "antmicroResistors0402:R_49R9_0402")
		(at 74.93 106.68 0)
		(mirror y)
		(unit 1)
		(exclude_from_sim no)
		(in_bom yes)
		(on_board yes)
		(dnp no)
		(property "Reference" "R44"
			(at 69.215 108.585 0)
			(effects
				(font
					(size 1.27 1.27)
					(thickness 0.15)
				)
			)
		)
		(property "Value" "R_49R9_0402"
			(at 54.61 119.38 0)
			(effects
				(font
					(size 1.27 1.27)
					(thickness 0.15)
				)
				(justify left bottom)
				(hide yes)
			)
		)
		(property "Footprint" "antmicro-footprints:R_0402_1005Metric"
			(at 54.61 121.92 0)
			(effects
				(font
					(size 1.27 1.27)
					(thickness 0.15)
				)
				(justify left bottom)
				(hide yes)
			)
		)
		(property "Datasheet" "https://www.bourns.com/docs/product-datasheets/cr.pdf"
			(at 54.61 124.46 0)
			(effects
				(font
					(size 1.27 1.27)
					(thickness 0.15)
				)
				(justify left bottom)
				(hide yes)
			)
		)
		(property "Description" "SMD Chip Resistor, 49.9 ohm, ± 1%, 62.5 mW, 0402 [1005 Metric], Thick Film, General Purpose"
			(at 74.93 106.68 0)
			(effects
				(font
					(size 1.27 1.27)
				)
				(hide yes)
			)
		)
		(property "MPN" "CR0402-FX-49R9GLF"
			(at 54.61 127 0)
			(effects
				(font
					(size 1.27 1.27)
					(thickness 0.15)
				)
				(justify left bottom)
				(hide yes)
			)
		)
		(property "Manufacturer" "Bourns"
			(at 54.61 129.54 0)
			(effects
				(font
					(size 1.27 1.27)
					(thickness 0.15)
				)
				(justify left bottom)
				(hide yes)
			)
		)
		(property "License" "Apache-2.0"
			(at 54.61 132.08 0)
			(effects
				(font
					(size 1.27 1.27)
					(thickness 0.15)
				)
				(justify left bottom)
				(hide yes)
			)
		)
		(property "Author" "Antmicro"
			(at 54.61 134.62 0)
			(effects
				(font
					(size 1.27 1.27)
					(thickness 0.15)
				)
				(justify left bottom)
				(hide yes)
			)
		)
		(property "Val" "49R9"
			(at 74.295 108.585 0)
			(effects
				(font
					(size 1.27 1.27)
					(thickness 0.15)
				)
			)
		)
		(property "Tolerance" "1%"
			(at 54.61 116.84 0)
			(effects
				(font
					(size 1.27 1.27)
				)
				(justify left bottom)
				(hide yes)
			)
		)
		(pin "1"
		)
		(pin "2"
		)
		(instances
			(project "gmsl-deserializer"
				(path ""
					(reference "R44")
					(unit 1)
				)
			)
		)
	)
	(symbol
		(lib_id "antmicroCapacitors0402:C_100n_0402")
		(at 86.36 96.52 180)
		(unit 1)
		(exclude_from_sim no)
		(in_bom yes)
		(on_board yes)
		(dnp no)
		(property "Reference" "C27"
			(at 82.55 95.25 0)
			(effects
				(font
					(size 1.27 1.27)
					(thickness 0.15)
				)
				(justify left)
			)
		)
		(property "Value" "C_100n_0402"
			(at 66.04 86.36 0)
			(effects
				(font
					(size 1.27 1.27)
					(thickness 0.15)
				)
				(justify left bottom)
				(hide yes)
			)
		)
		(property "Footprint" "antmicro-footprints:C_0402_1005Metric"
			(at 66.04 83.82 0)
			(effects
				(font
					(size 1.27 1.27)
					(thickness 0.15)
				)
				(justify left bottom)
				(hide yes)
			)
		)
		(property "Datasheet" "https://www.murata.com/products/productdetail?partno=GRM155R61H104KE14%23"
			(at 66.04 81.28 0)
			(effects
				(font
					(size 1.27 1.27)
					(thickness 0.15)
				)
				(justify left bottom)
				(hide yes)
			)
		)
		(property "Description" "SMD Multilayer Ceramic Capacitor, 0.1 µF, 50 V, 0402 [1005 Metric], ± 10%, X5R, GRM Series"
			(at 86.36 96.52 0)
			(effects
				(font
					(size 1.27 1.27)
				)
				(hide yes)
			)
		)
		(property "MPN" "GRM155R61H104KE14D"
			(at 66.04 78.74 0)
			(effects
				(font
					(size 1.27 1.27)
					(thickness 0.15)
				)
				(justify left bottom)
				(hide yes)
			)
		)
		(property "Manufacturer" "Murata"
			(at 66.04 76.2 0)
			(effects
				(font
					(size 1.27 1.27)
					(thickness 0.15)
				)
				(justify left bottom)
				(hide yes)
			)
		)
		(property "License" "Apache-2.0"
			(at 66.04 73.66 0)
			(effects
				(font
					(size 1.27 1.27)
					(thickness 0.15)
				)
				(justify left bottom)
				(hide yes)
			)
		)
		(property "Author" "Antmicro"
			(at 66.04 71.12 0)
			(effects
				(font
					(size 1.27 1.27)
					(thickness 0.15)
				)
				(justify left bottom)
				(hide yes)
			)
		)
		(property "Val" "100n"
			(at 85.09 95.25 0)
			(effects
				(font
					(size 1.27 1.27)
					(thickness 0.15)
				)
				(justify right)
			)
		)
		(property "Voltage" "50V"
			(at 66.04 68.58 0)
			(effects
				(font
					(size 1.27 1.27)
				)
				(justify left bottom)
				(hide yes)
			)
		)
		(property "Dielectric" "X5R"
			(at 66.04 66.04 0)
			(effects
				(font
					(size 1.27 1.27)
				)
				(justify left bottom)
				(hide yes)
			)
		)
		(pin "1"
		)
		(pin "2"
		)
		(instances
			(project "gmsl-deserializer"
				(path ""
					(reference "C27")
					(unit 1)
				)
			)
		)
	)
	(symbol
		(lib_id "antmicropower:GND")
		(at 162.56 193.04 0)
		(unit 1)
		(exclude_from_sim no)
		(in_bom yes)
		(on_board yes)
		(dnp no)
		(property "Reference" "#PWR073"
			(at 171.45 195.58 0)
			(effects
				(font
					(size 1.27 1.27)
					(thickness 0.15)
				)
				(justify left bottom)
				(hide yes)
			)
		)
		(property "Value" "GND"
			(at 162.56 196.85 0)
			(effects
				(font
					(size 1.27 1.27)
					(thickness 0.15)
				)
			)
		)
		(property "Footprint" ""
			(at 171.45 200.66 0)
			(effects
				(font
					(size 1.27 1.27)
					(thickness 0.15)
				)
				(justify left bottom)
				(hide yes)
			)
		)
		(property "Datasheet" ""
			(at 171.45 205.74 0)
			(effects
				(font
					(size 1.27 1.27)
					(thickness 0.15)
				)
				(justify left bottom)
				(hide yes)
			)
		)
		(property "Description" ""
			(at 162.56 193.04 0)
			(effects
				(font
					(size 1.27 1.27)
				)
				(hide yes)
			)
		)
		(property "Author" "Antmicro"
			(at 171.45 200.66 0)
			(effects
				(font
					(size 1.27 1.27)
					(thickness 0.15)
				)
				(justify left bottom)
				(hide yes)
			)
		)
		(property "License" "Apache-2.0"
			(at 171.45 203.2 0)
			(effects
				(font
					(size 1.27 1.27)
					(thickness 0.15)
				)
				(justify left bottom)
				(hide yes)
			)
		)
		(pin "1"
		)
		(instances
			(project "gmsl-deserializer"
				(path ""
					(reference "#PWR073")
					(unit 1)
				)
			)
		)
	)
	(symbol
		(lib_id "antmicroCapacitors0402:C_10u_0402")
		(at 223.52 121.92 90)
		(unit 1)
		(exclude_from_sim no)
		(in_bom yes)
		(on_board yes)
		(dnp no)
		(property "Reference" "C37"
			(at 224.155 117.475 90)
			(effects
				(font
					(size 1.27 1.27)
					(thickness 0.15)
				)
				(justify right)
			)
		)
		(property "Value" "C_10u_0402"
			(at 233.68 101.6 0)
			(effects
				(font
					(size 1.27 1.27)
					(thickness 0.15)
				)
				(justify left bottom)
				(hide yes)
			)
		)
		(property "Footprint" "antmicro-footprints:C_0402_1005Metric"
			(at 236.22 101.6 0)
			(effects
				(font
					(size 1.27 1.27)
					(thickness 0.15)
				)
				(justify left bottom)
				(hide yes)
			)
		)
		(property "Datasheet" "https://www.yageo.com/en/Chart/Download/pdf/CC0402MRX5R5BB106"
			(at 238.76 101.6 0)
			(effects
				(font
					(size 1.27 1.27)
					(thickness 0.15)
				)
				(justify left bottom)
				(hide yes)
			)
		)
		(property "Description" "SMD Multilayer Ceramic Capacitor, 10 µF, 6.3 V, 0402 [1005 Metric], ± 20%, X5R, CC Series"
			(at 223.52 121.92 0)
			(effects
				(font
					(size 1.27 1.27)
				)
				(hide yes)
			)
		)
		(property "MPN" "CC0402MRX5R5BB106"
			(at 241.3 101.6 0)
			(effects
				(font
					(size 1.27 1.27)
					(thickness 0.15)
				)
				(justify left bottom)
				(hide yes)
			)
		)
		(property "Manufacturer" "YAGEO"
			(at 243.84 101.6 0)
			(effects
				(font
					(size 1.27 1.27)
					(thickness 0.15)
				)
				(justify left bottom)
				(hide yes)
			)
		)
		(property "License" "Apache-2.0"
			(at 246.38 101.6 0)
			(effects
				(font
					(size 1.27 1.27)
					(thickness 0.15)
				)
				(justify left bottom)
				(hide yes)
			)
		)
		(property "Author" "Antmicro"
			(at 248.92 101.6 0)
			(effects
				(font
					(size 1.27 1.27)
					(thickness 0.15)
				)
				(justify left bottom)
				(hide yes)
			)
		)
		(property "Val" "10u"
			(at 224.155 121.285 90)
			(effects
				(font
					(size 1.27 1.27)
					(thickness 0.15)
				)
				(justify right)
			)
		)
		(property "Voltage" ""
			(at 251.46 101.6 0)
			(effects
				(font
					(size 1.27 1.27)
				)
				(justify left bottom)
				(hide yes)
			)
		)
		(property "Dielectric" ""
			(at 254 101.6 0)
			(effects
				(font
					(size 1.27 1.27)
				)
				(justify left bottom)
				(hide yes)
			)
		)
		(pin "1"
		)
		(pin "2"
		)
		(instances
			(project "gmsl-deserializer"
				(path ""
					(reference "C37")
					(unit 1)
				)
			)
		)
	)
	(symbol
		(lib_id "antmicroCapacitors0402:C_100n_0402")
		(at 91.44 99.06 180)
		(unit 1)
		(exclude_from_sim no)
		(in_bom yes)
		(on_board yes)
		(dnp no)
		(property "Reference" "C32"
			(at 87.63 100.33 0)
			(effects
				(font
					(size 1.27 1.27)
					(thickness 0.15)
				)
				(justify left)
			)
		)
		(property "Value" "C_100n_0402"
			(at 71.12 88.9 0)
			(effects
				(font
					(size 1.27 1.27)
					(thickness 0.15)
				)
				(justify left bottom)
				(hide yes)
			)
		)
		(property "Footprint" "antmicro-footprints:C_0402_1005Metric"
			(at 71.12 86.36 0)
			(effects
				(font
					(size 1.27 1.27)
					(thickness 0.15)
				)
				(justify left bottom)
				(hide yes)
			)
		)
		(property "Datasheet" "https://www.murata.com/products/productdetail?partno=GRM155R61H104KE14%23"
			(at 71.12 83.82 0)
			(effects
				(font
					(size 1.27 1.27)
					(thickness 0.15)
				)
				(justify left bottom)
				(hide yes)
			)
		)
		(property "Description" "SMD Multilayer Ceramic Capacitor, 0.1 µF, 50 V, 0402 [1005 Metric], ± 10%, X5R, GRM Series"
			(at 91.44 99.06 0)
			(effects
				(font
					(size 1.27 1.27)
				)
				(hide yes)
			)
		)
		(property "MPN" "GRM155R61H104KE14D"
			(at 71.12 81.28 0)
			(effects
				(font
					(size 1.27 1.27)
					(thickness 0.15)
				)
				(justify left bottom)
				(hide yes)
			)
		)
		(property "Manufacturer" "Murata"
			(at 71.12 78.74 0)
			(effects
				(font
					(size 1.27 1.27)
					(thickness 0.15)
				)
				(justify left bottom)
				(hide yes)
			)
		)
		(property "License" "Apache-2.0"
			(at 71.12 76.2 0)
			(effects
				(font
					(size 1.27 1.27)
					(thickness 0.15)
				)
				(justify left bottom)
				(hide yes)
			)
		)
		(property "Author" "Antmicro"
			(at 71.12 73.66 0)
			(effects
				(font
					(size 1.27 1.27)
					(thickness 0.15)
				)
				(justify left bottom)
				(hide yes)
			)
		)
		(property "Val" "100n"
			(at 90.17 100.33 0)
			(effects
				(font
					(size 1.27 1.27)
					(thickness 0.15)
				)
				(justify right)
			)
		)
		(property "Voltage" "50V"
			(at 71.12 71.12 0)
			(effects
				(font
					(size 1.27 1.27)
				)
				(justify left bottom)
				(hide yes)
			)
		)
		(property "Dielectric" "X5R"
			(at 71.12 68.58 0)
			(effects
				(font
					(size 1.27 1.27)
				)
				(justify left bottom)
				(hide yes)
			)
		)
		(pin "1"
		)
		(pin "2"
		)
		(instances
			(project "gmsl-deserializer"
				(path ""
					(reference "C32")
					(unit 1)
				)
			)
		)
	)
	(symbol
		(lib_id "antmicropower:GND")
		(at 85.09 190.5 0)
		(unit 1)
		(exclude_from_sim no)
		(in_bom yes)
		(on_board yes)
		(dnp no)
		(property "Reference" "#PWR069"
			(at 93.98 193.04 0)
			(effects
				(font
					(size 1.27 1.27)
					(thickness 0.15)
				)
				(justify left bottom)
				(hide yes)
			)
		)
		(property "Value" "GND"
			(at 85.09 194.31 0)
			(effects
				(font
					(size 1.27 1.27)
					(thickness 0.15)
				)
			)
		)
		(property "Footprint" ""
			(at 93.98 198.12 0)
			(effects
				(font
					(size 1.27 1.27)
					(thickness 0.15)
				)
				(justify left bottom)
				(hide yes)
			)
		)
		(property "Datasheet" ""
			(at 93.98 203.2 0)
			(effects
				(font
					(size 1.27 1.27)
					(thickness 0.15)
				)
				(justify left bottom)
				(hide yes)
			)
		)
		(property "Description" ""
			(at 85.09 190.5 0)
			(effects
				(font
					(size 1.27 1.27)
				)
				(hide yes)
			)
		)
		(property "Author" "Antmicro"
			(at 93.98 198.12 0)
			(effects
				(font
					(size 1.27 1.27)
					(thickness 0.15)
				)
				(justify left bottom)
				(hide yes)
			)
		)
		(property "License" "Apache-2.0"
			(at 93.98 200.66 0)
			(effects
				(font
					(size 1.27 1.27)
					(thickness 0.15)
				)
				(justify left bottom)
				(hide yes)
			)
		)
		(pin "1"
		)
		(instances
			(project "gmsl-deserializer"
				(path ""
					(reference "#PWR069")
					(unit 1)
				)
			)
		)
	)
	(symbol
		(lib_id "antmicroCapacitors0402:C_100n_0402")
		(at 252.73 200.66 90)
		(unit 1)
		(exclude_from_sim no)
		(in_bom yes)
		(on_board yes)
		(dnp no)
		(property "Reference" "C47"
			(at 253.365 196.215 90)
			(effects
				(font
					(size 1.27 1.27)
					(thickness 0.15)
				)
				(justify right)
			)
		)
		(property "Value" "C_100n_0402"
			(at 262.89 180.34 0)
			(effects
				(font
					(size 1.27 1.27)
					(thickness 0.15)
				)
				(justify left bottom)
				(hide yes)
			)
		)
		(property "Footprint" "antmicro-footprints:C_0402_1005Metric"
			(at 265.43 180.34 0)
			(effects
				(font
					(size 1.27 1.27)
					(thickness 0.15)
				)
				(justify left bottom)
				(hide yes)
			)
		)
		(property "Datasheet" "https://www.murata.com/products/productdetail?partno=GRM155R61H104KE14%23"
			(at 267.97 180.34 0)
			(effects
				(font
					(size 1.27 1.27)
					(thickness 0.15)
				)
				(justify left bottom)
				(hide yes)
			)
		)
		(property "Description" "SMD Multilayer Ceramic Capacitor, 0.1 µF, 50 V, 0402 [1005 Metric], ± 10%, X5R, GRM Series"
			(at 252.73 200.66 0)
			(effects
				(font
					(size 1.27 1.27)
				)
				(hide yes)
			)
		)
		(property "MPN" "GRM155R61H104KE14D"
			(at 270.51 180.34 0)
			(effects
				(font
					(size 1.27 1.27)
					(thickness 0.15)
				)
				(justify left bottom)
				(hide yes)
			)
		)
		(property "Manufacturer" "Murata"
			(at 273.05 180.34 0)
			(effects
				(font
					(size 1.27 1.27)
					(thickness 0.15)
				)
				(justify left bottom)
				(hide yes)
			)
		)
		(property "License" "Apache-2.0"
			(at 275.59 180.34 0)
			(effects
				(font
					(size 1.27 1.27)
					(thickness 0.15)
				)
				(justify left bottom)
				(hide yes)
			)
		)
		(property "Author" "Antmicro"
			(at 278.13 180.34 0)
			(effects
				(font
					(size 1.27 1.27)
					(thickness 0.15)
				)
				(justify left bottom)
				(hide yes)
			)
		)
		(property "Val" "100n"
			(at 253.365 200.025 90)
			(effects
				(font
					(size 1.27 1.27)
					(thickness 0.15)
				)
				(justify right)
			)
		)
		(property "Voltage" "50V"
			(at 280.67 180.34 0)
			(effects
				(font
					(size 1.27 1.27)
				)
				(justify left bottom)
				(hide yes)
			)
		)
		(property "Dielectric" "X5R"
			(at 283.21 180.34 0)
			(effects
				(font
					(size 1.27 1.27)
				)
				(justify left bottom)
				(hide yes)
			)
		)
		(pin "1"
		)
		(pin "2"
		)
		(instances
			(project "gmsl-deserializer"
				(path ""
					(reference "C47")
					(unit 1)
				)
			)
		)
	)
	(symbol
		(lib_id "antmicroCapacitors0402:C_100n_0402")
		(at 91.44 114.3 180)
		(unit 1)
		(exclude_from_sim no)
		(in_bom yes)
		(on_board yes)
		(dnp no)
		(property "Reference" "C34"
			(at 87.63 115.57 0)
			(effects
				(font
					(size 1.27 1.27)
					(thickness 0.15)
				)
				(justify left)
			)
		)
		(property "Value" "C_100n_0402"
			(at 71.12 104.14 0)
			(effects
				(font
					(size 1.27 1.27)
					(thickness 0.15)
				)
				(justify left bottom)
				(hide yes)
			)
		)
		(property "Footprint" "antmicro-footprints:C_0402_1005Metric"
			(at 71.12 101.6 0)
			(effects
				(font
					(size 1.27 1.27)
					(thickness 0.15)
				)
				(justify left bottom)
				(hide yes)
			)
		)
		(property "Datasheet" "https://www.murata.com/products/productdetail?partno=GRM155R61H104KE14%23"
			(at 71.12 99.06 0)
			(effects
				(font
					(size 1.27 1.27)
					(thickness 0.15)
				)
				(justify left bottom)
				(hide yes)
			)
		)
		(property "Description" "SMD Multilayer Ceramic Capacitor, 0.1 µF, 50 V, 0402 [1005 Metric], ± 10%, X5R, GRM Series"
			(at 91.44 114.3 0)
			(effects
				(font
					(size 1.27 1.27)
				)
				(hide yes)
			)
		)
		(property "MPN" "GRM155R61H104KE14D"
			(at 71.12 96.52 0)
			(effects
				(font
					(size 1.27 1.27)
					(thickness 0.15)
				)
				(justify left bottom)
				(hide yes)
			)
		)
		(property "Manufacturer" "Murata"
			(at 71.12 93.98 0)
			(effects
				(font
					(size 1.27 1.27)
					(thickness 0.15)
				)
				(justify left bottom)
				(hide yes)
			)
		)
		(property "License" "Apache-2.0"
			(at 71.12 91.44 0)
			(effects
				(font
					(size 1.27 1.27)
					(thickness 0.15)
				)
				(justify left bottom)
				(hide yes)
			)
		)
		(property "Author" "Antmicro"
			(at 71.12 88.9 0)
			(effects
				(font
					(size 1.27 1.27)
					(thickness 0.15)
				)
				(justify left bottom)
				(hide yes)
			)
		)
		(property "Val" "100n"
			(at 90.17 115.57 0)
			(effects
				(font
					(size 1.27 1.27)
					(thickness 0.15)
				)
				(justify right)
			)
		)
		(property "Voltage" "50V"
			(at 71.12 86.36 0)
			(effects
				(font
					(size 1.27 1.27)
				)
				(justify left bottom)
				(hide yes)
			)
		)
		(property "Dielectric" "X5R"
			(at 71.12 83.82 0)
			(effects
				(font
					(size 1.27 1.27)
				)
				(justify left bottom)
				(hide yes)
			)
		)
		(pin "1"
		)
		(pin "2"
		)
		(instances
			(project "gmsl-deserializer"
				(path ""
					(reference "C34")
					(unit 1)
				)
			)
		)
	)
	(symbol
		(lib_id "antmicropower:GND")
		(at 265.43 207.01 0)
		(unit 1)
		(exclude_from_sim no)
		(in_bom yes)
		(on_board yes)
		(dnp no)
		(property "Reference" "#PWR090"
			(at 274.32 209.55 0)
			(effects
				(font
					(size 1.27 1.27)
					(thickness 0.15)
				)
				(justify left bottom)
				(hide yes)
			)
		)
		(property "Value" "GND"
			(at 265.43 210.82 0)
			(effects
				(font
					(size 1.27 1.27)
					(thickness 0.15)
				)
			)
		)
		(property "Footprint" ""
			(at 274.32 214.63 0)
			(effects
				(font
					(size 1.27 1.27)
					(thickness 0.15)
				)
				(justify left bottom)
				(hide yes)
			)
		)
		(property "Datasheet" ""
			(at 274.32 219.71 0)
			(effects
				(font
					(size 1.27 1.27)
					(thickness 0.15)
				)
				(justify left bottom)
				(hide yes)
			)
		)
		(property "Description" ""
			(at 265.43 207.01 0)
			(effects
				(font
					(size 1.27 1.27)
				)
				(hide yes)
			)
		)
		(property "Author" "Antmicro"
			(at 274.32 214.63 0)
			(effects
				(font
					(size 1.27 1.27)
					(thickness 0.15)
				)
				(justify left bottom)
				(hide yes)
			)
		)
		(property "License" "Apache-2.0"
			(at 274.32 217.17 0)
			(effects
				(font
					(size 1.27 1.27)
					(thickness 0.15)
				)
				(justify left bottom)
				(hide yes)
			)
		)
		(pin "1"
		)
		(instances
			(project "gmsl-deserializer"
				(path ""
					(reference "#PWR090")
					(unit 1)
				)
			)
		)
	)
	(symbol
		(lib_id "antmicroResistors0402:R_0R_0402")
		(at 370.84 95.25 90)
		(unit 1)
		(exclude_from_sim no)
		(in_bom yes)
		(on_board yes)
		(dnp no)
		(property "Reference" "R56"
			(at 372.745 91.44 90)
			(effects
				(font
					(size 1.27 1.27)
					(thickness 0.15)
				)
				(justify right)
			)
		)
		(property "Value" "R_0R_0402"
			(at 383.54 74.93 0)
			(effects
				(font
					(size 1.27 1.27)
					(thickness 0.15)
				)
				(justify left bottom)
				(hide yes)
			)
		)
		(property "Footprint" "antmicro-footprints:R_0402_1005Metric"
			(at 386.08 74.93 0)
			(effects
				(font
					(size 1.27 1.27)
					(thickness 0.15)
				)
				(justify left bottom)
				(hide yes)
			)
		)
		(property "Datasheet" "https://industrial.panasonic.com/cdbs/www-data/pdf/RDA0000/AOA0000C301.pdf"
			(at 388.62 74.93 0)
			(effects
				(font
					(size 1.27 1.27)
					(thickness 0.15)
				)
				(justify left bottom)
				(hide yes)
			)
		)
		(property "Description" "SMD Chip Resistor, Jumper, 0 ohm, 100 mW, 0402 [1005 Metric], Thick Film, General Purpose"
			(at 370.84 95.25 0)
			(effects
				(font
					(size 1.27 1.27)
				)
				(hide yes)
			)
		)
		(property "MPN" "ERJ2GE0R00X"
			(at 391.16 74.93 0)
			(effects
				(font
					(size 1.27 1.27)
					(thickness 0.15)
				)
				(justify left bottom)
				(hide yes)
			)
		)
		(property "Manufacturer" "Panasonic"
			(at 393.7 74.93 0)
			(effects
				(font
					(size 1.27 1.27)
					(thickness 0.15)
				)
				(justify left bottom)
				(hide yes)
			)
		)
		(property "License" "Apache-2.0"
			(at 396.24 74.93 0)
			(effects
				(font
					(size 1.27 1.27)
					(thickness 0.15)
				)
				(justify left bottom)
				(hide yes)
			)
		)
		(property "Author" "Antmicro"
			(at 398.78 74.93 0)
			(effects
				(font
					(size 1.27 1.27)
					(thickness 0.15)
				)
				(justify left bottom)
				(hide yes)
			)
		)
		(property "Val" "0R"
			(at 372.745 93.98 90)
			(effects
				(font
					(size 1.27 1.27)
					(thickness 0.15)
				)
				(justify right)
			)
		)
		(property "Tolerance" "~"
			(at 381 74.93 0)
			(effects
				(font
					(size 1.27 1.27)
				)
				(justify left bottom)
				(hide yes)
			)
		)
		(property "Current" "1A"
			(at 401.32 74.93 0)
			(effects
				(font
					(size 1.27 1.27)
					(thickness 0.15)
				)
				(justify left bottom)
				(hide yes)
			)
		)
		(pin "1"
		)
		(pin "2"
		)
		(instances
			(project "gmsl-deserializer"
				(path ""
					(reference "R56")
					(unit 1)
				)
			)
		)
	)
	(symbol
		(lib_id "antmicroResonators:Resonator_25MHz_ABM8G")
		(at 81.28 182.88 0)
		(unit 1)
		(exclude_from_sim no)
		(in_bom yes)
		(on_board yes)
		(dnp no)
		(property "Reference" "Y1"
			(at 85.09 176.53 0)
			(effects
				(font
					(size 1.27 1.27)
					(thickness 0.15)
				)
			)
		)
		(property "Value" "Resonator_25MHz_ABM8G"
			(at 96.52 195.58 0)
			(effects
				(font
					(size 1.27 1.27)
					(thickness 0.15)
				)
				(justify left bottom)
				(hide yes)
			)
		)
		(property "Footprint" "antmicro-footprints:Resonator_SMD_Abracon_ABM8G_3.2x2.5mm"
			(at 96.52 198.12 0)
			(effects
				(font
					(size 1.27 1.27)
					(thickness 0.15)
				)
				(justify left bottom)
				(hide yes)
			)
		)
		(property "Datasheet" "https://abracon.com/Resonators/ABM8G.pdf"
			(at 96.52 200.66 0)
			(effects
				(font
					(size 1.27 1.27)
					(thickness 0.15)
				)
				(justify left bottom)
				(hide yes)
			)
		)
		(property "Description" "Crystal, 25 MHz, SMD, 3.2mm x 2.5mm, 30 ppm, 18 pF, 20 ppm, ABM8G"
			(at 81.28 182.88 0)
			(effects
				(font
					(size 1.27 1.27)
				)
				(hide yes)
			)
		)
		(property "MPN" "ABM8G-25.000MHZ-18-D2Y-T3"
			(at 96.52 190.5 0)
			(effects
				(font
					(size 1.27 1.27)
					(thickness 0.15)
				)
				(justify left bottom)
				(hide yes)
			)
		)
		(property "Manufacturer" "Abracon"
			(at 96.52 203.2 0)
			(effects
				(font
					(size 1.27 1.27)
					(thickness 0.15)
				)
				(justify left bottom)
				(hide yes)
			)
		)
		(property "Author" "Antmicro"
			(at 96.52 205.74 0)
			(effects
				(font
					(size 1.27 1.27)
					(thickness 0.15)
				)
				(justify left bottom)
				(hide yes)
			)
		)
		(property "License" "Apache-2.0"
			(at 96.52 208.28 0)
			(effects
				(font
					(size 1.27 1.27)
					(thickness 0.15)
				)
				(justify left bottom)
				(hide yes)
			)
		)
		(property "Val" "25 MHz"
			(at 85.09 179.07 0)
			(effects
				(font
					(size 1.27 1.27)
					(thickness 0.15)
				)
			)
		)
		(pin "1"
		)
		(pin "2"
		)
		(pin "3"
		)
		(pin "4"
		)
		(instances
			(project "gmsl-deserializer"
				(path ""
					(reference "Y1")
					(unit 1)
				)
			)
		)
	)
	(symbol
		(lib_id "antmicropower:GND")
		(at 341.63 104.14 0)
		(mirror y)
		(unit 1)
		(exclude_from_sim no)
		(in_bom yes)
		(on_board yes)
		(dnp no)
		(property "Reference" "#PWR092"
			(at 332.74 106.68 0)
			(effects
				(font
					(size 1.27 1.27)
					(thickness 0.15)
				)
				(justify left bottom)
				(hide yes)
			)
		)
		(property "Value" "GND"
			(at 341.63 107.95 0)
			(effects
				(font
					(size 1.27 1.27)
					(thickness 0.15)
				)
			)
		)
		(property "Footprint" ""
			(at 332.74 111.76 0)
			(effects
				(font
					(size 1.27 1.27)
					(thickness 0.15)
				)
				(justify left bottom)
				(hide yes)
			)
		)
		(property "Datasheet" ""
			(at 332.74 116.84 0)
			(effects
				(font
					(size 1.27 1.27)
					(thickness 0.15)
				)
				(justify left bottom)
				(hide yes)
			)
		)
		(property "Description" ""
			(at 341.63 104.14 0)
			(effects
				(font
					(size 1.27 1.27)
				)
				(hide yes)
			)
		)
		(property "Author" "Antmicro"
			(at 332.74 111.76 0)
			(effects
				(font
					(size 1.27 1.27)
					(thickness 0.15)
				)
				(justify left bottom)
				(hide yes)
			)
		)
		(property "License" "Apache-2.0"
			(at 332.74 114.3 0)
			(effects
				(font
					(size 1.27 1.27)
					(thickness 0.15)
				)
				(justify left bottom)
				(hide yes)
			)
		)
		(pin "1"
		)
		(instances
			(project "gmsl-deserializer"
				(path ""
					(reference "#PWR092")
					(unit 1)
				)
			)
		)
	)
	(symbol
		(lib_id "antmicropower:GND")
		(at 353.06 125.73 0)
		(mirror y)
		(unit 1)
		(exclude_from_sim no)
		(in_bom yes)
		(on_board yes)
		(dnp no)
		(property "Reference" "#PWR095"
			(at 344.17 128.27 0)
			(effects
				(font
					(size 1.27 1.27)
					(thickness 0.15)
				)
				(justify left bottom)
				(hide yes)
			)
		)
		(property "Value" "GND"
			(at 353.06 129.54 0)
			(effects
				(font
					(size 1.27 1.27)
					(thickness 0.15)
				)
			)
		)
		(property "Footprint" ""
			(at 344.17 133.35 0)
			(effects
				(font
					(size 1.27 1.27)
					(thickness 0.15)
				)
				(justify left bottom)
				(hide yes)
			)
		)
		(property "Datasheet" ""
			(at 344.17 138.43 0)
			(effects
				(font
					(size 1.27 1.27)
					(thickness 0.15)
				)
				(justify left bottom)
				(hide yes)
			)
		)
		(property "Description" ""
			(at 353.06 125.73 0)
			(effects
				(font
					(size 1.27 1.27)
				)
				(hide yes)
			)
		)
		(property "Author" "Antmicro"
			(at 344.17 133.35 0)
			(effects
				(font
					(size 1.27 1.27)
					(thickness 0.15)
				)
				(justify left bottom)
				(hide yes)
			)
		)
		(property "License" "Apache-2.0"
			(at 344.17 135.89 0)
			(effects
				(font
					(size 1.27 1.27)
					(thickness 0.15)
				)
				(justify left bottom)
				(hide yes)
			)
		)
		(pin "1"
		)
		(instances
			(project "gmsl-deserializer"
				(path ""
					(reference "#PWR095")
					(unit 1)
				)
			)
		)
	)
	(symbol
		(lib_id "antmicropower:GND")
		(at 66.04 114.3 0)
		(unit 1)
		(exclude_from_sim no)
		(in_bom yes)
		(on_board yes)
		(dnp no)
		(property "Reference" "#PWR067"
			(at 74.93 116.84 0)
			(effects
				(font
					(size 1.27 1.27)
					(thickness 0.15)
				)
				(justify left bottom)
				(hide yes)
			)
		)
		(property "Value" "GND"
			(at 66.04 118.11 0)
			(effects
				(font
					(size 1.27 1.27)
					(thickness 0.15)
				)
			)
		)
		(property "Footprint" ""
			(at 74.93 121.92 0)
			(effects
				(font
					(size 1.27 1.27)
					(thickness 0.15)
				)
				(justify left bottom)
				(hide yes)
			)
		)
		(property "Datasheet" ""
			(at 74.93 127 0)
			(effects
				(font
					(size 1.27 1.27)
					(thickness 0.15)
				)
				(justify left bottom)
				(hide yes)
			)
		)
		(property "Description" ""
			(at 66.04 114.3 0)
			(effects
				(font
					(size 1.27 1.27)
				)
				(hide yes)
			)
		)
		(property "Author" "Antmicro"
			(at 74.93 121.92 0)
			(effects
				(font
					(size 1.27 1.27)
					(thickness 0.15)
				)
				(justify left bottom)
				(hide yes)
			)
		)
		(property "License" "Apache-2.0"
			(at 74.93 124.46 0)
			(effects
				(font
					(size 1.27 1.27)
					(thickness 0.15)
				)
				(justify left bottom)
				(hide yes)
			)
		)
		(pin "1"
		)
		(instances
			(project "gmsl-deserializer"
				(path ""
					(reference "#PWR067")
					(unit 1)
				)
			)
		)
	)
	(symbol
		(lib_id "antmicroResistors0402:R_49R9_0402")
		(at 74.93 99.06 0)
		(mirror y)
		(unit 1)
		(exclude_from_sim no)
		(in_bom yes)
		(on_board yes)
		(dnp no)
		(property "Reference" "R43"
			(at 69.215 100.965 0)
			(effects
				(font
					(size 1.27 1.27)
					(thickness 0.15)
				)
			)
		)
		(property "Value" "R_49R9_0402"
			(at 54.61 111.76 0)
			(effects
				(font
					(size 1.27 1.27)
					(thickness 0.15)
				)
				(justify left bottom)
				(hide yes)
			)
		)
		(property "Footprint" "antmicro-footprints:R_0402_1005Metric"
			(at 54.61 114.3 0)
			(effects
				(font
					(size 1.27 1.27)
					(thickness 0.15)
				)
				(justify left bottom)
				(hide yes)
			)
		)
		(property "Datasheet" "https://www.bourns.com/docs/product-datasheets/cr.pdf"
			(at 54.61 116.84 0)
			(effects
				(font
					(size 1.27 1.27)
					(thickness 0.15)
				)
				(justify left bottom)
				(hide yes)
			)
		)
		(property "Description" "SMD Chip Resistor, 49.9 ohm, ± 1%, 62.5 mW, 0402 [1005 Metric], Thick Film, General Purpose"
			(at 74.93 99.06 0)
			(effects
				(font
					(size 1.27 1.27)
				)
				(hide yes)
			)
		)
		(property "MPN" "CR0402-FX-49R9GLF"
			(at 54.61 119.38 0)
			(effects
				(font
					(size 1.27 1.27)
					(thickness 0.15)
				)
				(justify left bottom)
				(hide yes)
			)
		)
		(property "Manufacturer" "Bourns"
			(at 54.61 121.92 0)
			(effects
				(font
					(size 1.27 1.27)
					(thickness 0.15)
				)
				(justify left bottom)
				(hide yes)
			)
		)
		(property "License" "Apache-2.0"
			(at 54.61 124.46 0)
			(effects
				(font
					(size 1.27 1.27)
					(thickness 0.15)
				)
				(justify left bottom)
				(hide yes)
			)
		)
		(property "Author" "Antmicro"
			(at 54.61 127 0)
			(effects
				(font
					(size 1.27 1.27)
					(thickness 0.15)
				)
				(justify left bottom)
				(hide yes)
			)
		)
		(property "Val" "49R9"
			(at 74.295 100.965 0)
			(effects
				(font
					(size 1.27 1.27)
					(thickness 0.15)
				)
			)
		)
		(property "Tolerance" "1%"
			(at 54.61 109.22 0)
			(effects
				(font
					(size 1.27 1.27)
				)
				(justify left bottom)
				(hide yes)
			)
		)
		(pin "1"
		)
		(pin "2"
		)
		(instances
			(project "gmsl-deserializer"
				(path ""
					(reference "R43")
					(unit 1)
				)
			)
		)
	)
	(symbol
		(lib_id "antmicroResistors0402:R_0R_0402")
		(at 370.84 116.84 90)
		(unit 1)
		(exclude_from_sim no)
		(in_bom yes)
		(on_board yes)
		(dnp no)
		(property "Reference" "R57"
			(at 372.745 113.03 90)
			(effects
				(font
					(size 1.27 1.27)
					(thickness 0.15)
				)
				(justify right)
			)
		)
		(property "Value" "R_0R_0402"
			(at 383.54 96.52 0)
			(effects
				(font
					(size 1.27 1.27)
					(thickness 0.15)
				)
				(justify left bottom)
				(hide yes)
			)
		)
		(property "Footprint" "antmicro-footprints:R_0402_1005Metric"
			(at 386.08 96.52 0)
			(effects
				(font
					(size 1.27 1.27)
					(thickness 0.15)
				)
				(justify left bottom)
				(hide yes)
			)
		)
		(property "Datasheet" "https://industrial.panasonic.com/cdbs/www-data/pdf/RDA0000/AOA0000C301.pdf"
			(at 388.62 96.52 0)
			(effects
				(font
					(size 1.27 1.27)
					(thickness 0.15)
				)
				(justify left bottom)
				(hide yes)
			)
		)
		(property "Description" "SMD Chip Resistor, Jumper, 0 ohm, 100 mW, 0402 [1005 Metric], Thick Film, General Purpose"
			(at 370.84 116.84 0)
			(effects
				(font
					(size 1.27 1.27)
				)
				(hide yes)
			)
		)
		(property "MPN" "ERJ2GE0R00X"
			(at 391.16 96.52 0)
			(effects
				(font
					(size 1.27 1.27)
					(thickness 0.15)
				)
				(justify left bottom)
				(hide yes)
			)
		)
		(property "Manufacturer" "Panasonic"
			(at 393.7 96.52 0)
			(effects
				(font
					(size 1.27 1.27)
					(thickness 0.15)
				)
				(justify left bottom)
				(hide yes)
			)
		)
		(property "License" "Apache-2.0"
			(at 396.24 96.52 0)
			(effects
				(font
					(size 1.27 1.27)
					(thickness 0.15)
				)
				(justify left bottom)
				(hide yes)
			)
		)
		(property "Author" "Antmicro"
			(at 398.78 96.52 0)
			(effects
				(font
					(size 1.27 1.27)
					(thickness 0.15)
				)
				(justify left bottom)
				(hide yes)
			)
		)
		(property "Val" "0R"
			(at 372.745 115.57 90)
			(effects
				(font
					(size 1.27 1.27)
					(thickness 0.15)
				)
				(justify right)
			)
		)
		(property "Tolerance" "~"
			(at 381 96.52 0)
			(effects
				(font
					(size 1.27 1.27)
				)
				(justify left bottom)
				(hide yes)
			)
		)
		(property "Current" "1A"
			(at 401.32 96.52 0)
			(effects
				(font
					(size 1.27 1.27)
					(thickness 0.15)
				)
				(justify left bottom)
				(hide yes)
			)
		)
		(pin "1"
		)
		(pin "2"
		)
		(instances
			(project "gmsl-deserializer"
				(path ""
					(reference "R57")
					(unit 1)
				)
			)
		)
	)
	(symbol
		(lib_id "antmicropower:+1V2")
		(at 214.63 107.95 0)
		(unit 1)
		(exclude_from_sim no)
		(in_bom yes)
		(on_board yes)
		(dnp no)
		(property "Reference" "#PWR075"
			(at 214.63 111.76 0)
			(effects
				(font
					(size 1.27 1.27)
				)
				(hide yes)
			)
		)
		(property "Value" "+1V2"
			(at 213.995 104.14 0)
			(effects
				(font
					(size 1.27 1.27)
				)
			)
		)
		(property "Footprint" ""
			(at 214.63 107.95 0)
			(effects
				(font
					(size 1.27 1.27)
				)
				(hide yes)
			)
		)
		(property "Datasheet" ""
			(at 214.63 107.95 0)
			(effects
				(font
					(size 1.27 1.27)
				)
				(hide yes)
			)
		)
		(property "Description" ""
			(at 214.63 107.95 0)
			(effects
				(font
					(size 1.27 1.27)
				)
				(hide yes)
			)
		)
		(pin "1"
		)
		(instances
			(project "gmsl-deserializer"
				(path ""
					(reference "#PWR075")
					(unit 1)
				)
			)
		)
	)
	(symbol
		(lib_id "antmicroCapacitors0402:C_100n_0402")
		(at 91.44 106.68 180)
		(unit 1)
		(exclude_from_sim no)
		(in_bom yes)
		(on_board yes)
		(dnp no)
		(property "Reference" "C33"
			(at 87.63 107.95 0)
			(effects
				(font
					(size 1.27 1.27)
					(thickness 0.15)
				)
				(justify left)
			)
		)
		(property "Value" "C_100n_0402"
			(at 71.12 96.52 0)
			(effects
				(font
					(size 1.27 1.27)
					(thickness 0.15)
				)
				(justify left bottom)
				(hide yes)
			)
		)
		(property "Footprint" "antmicro-footprints:C_0402_1005Metric"
			(at 71.12 93.98 0)
			(effects
				(font
					(size 1.27 1.27)
					(thickness 0.15)
				)
				(justify left bottom)
				(hide yes)
			)
		)
		(property "Datasheet" "https://www.murata.com/products/productdetail?partno=GRM155R61H104KE14%23"
			(at 71.12 91.44 0)
			(effects
				(font
					(size 1.27 1.27)
					(thickness 0.15)
				)
				(justify left bottom)
				(hide yes)
			)
		)
		(property "Description" "SMD Multilayer Ceramic Capacitor, 0.1 µF, 50 V, 0402 [1005 Metric], ± 10%, X5R, GRM Series"
			(at 91.44 106.68 0)
			(effects
				(font
					(size 1.27 1.27)
				)
				(hide yes)
			)
		)
		(property "MPN" "GRM155R61H104KE14D"
			(at 71.12 88.9 0)
			(effects
				(font
					(size 1.27 1.27)
					(thickness 0.15)
				)
				(justify left bottom)
				(hide yes)
			)
		)
		(property "Manufacturer" "Murata"
			(at 71.12 86.36 0)
			(effects
				(font
					(size 1.27 1.27)
					(thickness 0.15)
				)
				(justify left bottom)
				(hide yes)
			)
		)
		(property "License" "Apache-2.0"
			(at 71.12 83.82 0)
			(effects
				(font
					(size 1.27 1.27)
					(thickness 0.15)
				)
				(justify left bottom)
				(hide yes)
			)
		)
		(property "Author" "Antmicro"
			(at 71.12 81.28 0)
			(effects
				(font
					(size 1.27 1.27)
					(thickness 0.15)
				)
				(justify left bottom)
				(hide yes)
			)
		)
		(property "Val" "100n"
			(at 90.17 107.95 0)
			(effects
				(font
					(size 1.27 1.27)
					(thickness 0.15)
				)
				(justify right)
			)
		)
		(property "Voltage" "50V"
			(at 71.12 78.74 0)
			(effects
				(font
					(size 1.27 1.27)
				)
				(justify left bottom)
				(hide yes)
			)
		)
		(property "Dielectric" "X5R"
			(at 71.12 76.2 0)
			(effects
				(font
					(size 1.27 1.27)
				)
				(justify left bottom)
				(hide yes)
			)
		)
		(pin "1"
		)
		(pin "2"
		)
		(instances
			(project "gmsl-deserializer"
				(path ""
					(reference "C33")
					(unit 1)
				)
			)
		)
	)
	(symbol
		(lib_id "antmicroCapacitors0402:C_100n_0402")
		(at 86.36 104.14 180)
		(unit 1)
		(exclude_from_sim no)
		(in_bom yes)
		(on_board yes)
		(dnp no)
		(property "Reference" "C28"
			(at 82.55 102.87 0)
			(effects
				(font
					(size 1.27 1.27)
					(thickness 0.15)
				)
				(justify left)
			)
		)
		(property "Value" "C_100n_0402"
			(at 66.04 93.98 0)
			(effects
				(font
					(size 1.27 1.27)
					(thickness 0.15)
				)
				(justify left bottom)
				(hide yes)
			)
		)
		(property "Footprint" "antmicro-footprints:C_0402_1005Metric"
			(at 66.04 91.44 0)
			(effects
				(font
					(size 1.27 1.27)
					(thickness 0.15)
				)
				(justify left bottom)
				(hide yes)
			)
		)
		(property "Datasheet" "https://www.murata.com/products/productdetail?partno=GRM155R61H104KE14%23"
			(at 66.04 88.9 0)
			(effects
				(font
					(size 1.27 1.27)
					(thickness 0.15)
				)
				(justify left bottom)
				(hide yes)
			)
		)
		(property "Description" "SMD Multilayer Ceramic Capacitor, 0.1 µF, 50 V, 0402 [1005 Metric], ± 10%, X5R, GRM Series"
			(at 86.36 104.14 0)
			(effects
				(font
					(size 1.27 1.27)
				)
				(hide yes)
			)
		)
		(property "MPN" "GRM155R61H104KE14D"
			(at 66.04 86.36 0)
			(effects
				(font
					(size 1.27 1.27)
					(thickness 0.15)
				)
				(justify left bottom)
				(hide yes)
			)
		)
		(property "Manufacturer" "Murata"
			(at 66.04 83.82 0)
			(effects
				(font
					(size 1.27 1.27)
					(thickness 0.15)
				)
				(justify left bottom)
				(hide yes)
			)
		)
		(property "License" "Apache-2.0"
			(at 66.04 81.28 0)
			(effects
				(font
					(size 1.27 1.27)
					(thickness 0.15)
				)
				(justify left bottom)
				(hide yes)
			)
		)
		(property "Author" "Antmicro"
			(at 66.04 78.74 0)
			(effects
				(font
					(size 1.27 1.27)
					(thickness 0.15)
				)
				(justify left bottom)
				(hide yes)
			)
		)
		(property "Val" "100n"
			(at 85.09 102.87 0)
			(effects
				(font
					(size 1.27 1.27)
					(thickness 0.15)
				)
				(justify right)
			)
		)
		(property "Voltage" "50V"
			(at 66.04 76.2 0)
			(effects
				(font
					(size 1.27 1.27)
				)
				(justify left bottom)
				(hide yes)
			)
		)
		(property "Dielectric" "X5R"
			(at 66.04 73.66 0)
			(effects
				(font
					(size 1.27 1.27)
				)
				(justify left bottom)
				(hide yes)
			)
		)
		(pin "1"
		)
		(pin "2"
		)
		(instances
			(project "gmsl-deserializer"
				(path ""
					(reference "C28")
					(unit 1)
				)
			)
		)
	)
	(symbol
		(lib_id "antmicroResistors0402:R_10k_0402")
		(at 121.92 191.77 90)
		(unit 1)
		(exclude_from_sim no)
		(in_bom yes)
		(on_board yes)
		(dnp no)
		(property "Reference" "R49"
			(at 123.825 187.96 90)
			(effects
				(font
					(size 1.27 1.27)
					(thickness 0.15)
				)
				(justify right)
			)
		)
		(property "Value" "R_10k_0402"
			(at 134.62 171.45 0)
			(effects
				(font
					(size 1.27 1.27)
					(thickness 0.15)
				)
				(justify left bottom)
				(hide yes)
			)
		)
		(property "Footprint" "antmicro-footprints:R_0402_1005Metric"
			(at 137.16 171.45 0)
			(effects
				(font
					(size 1.27 1.27)
					(thickness 0.15)
				)
				(justify left bottom)
				(hide yes)
			)
		)
		(property "Datasheet" "https://www.bourns.com/docs/product-datasheets/cr.pdf"
			(at 139.7 171.45 0)
			(effects
				(font
					(size 1.27 1.27)
					(thickness 0.15)
				)
				(justify left bottom)
				(hide yes)
			)
		)
		(property "Description" "SMD Chip Resistor, 10 kohm, ± 1%, 62.5 mW, 0402 [1005 Metric], Thick Film, General Purpose"
			(at 121.92 191.77 0)
			(effects
				(font
					(size 1.27 1.27)
				)
				(hide yes)
			)
		)
		(property "MPN" "CR0402-FX-1002GLF"
			(at 142.24 171.45 0)
			(effects
				(font
					(size 1.27 1.27)
					(thickness 0.15)
				)
				(justify left bottom)
				(hide yes)
			)
		)
		(property "Manufacturer" "Bourns"
			(at 144.78 171.45 0)
			(effects
				(font
					(size 1.27 1.27)
					(thickness 0.15)
				)
				(justify left bottom)
				(hide yes)
			)
		)
		(property "License" "Apache-2.0"
			(at 147.32 171.45 0)
			(effects
				(font
					(size 1.27 1.27)
					(thickness 0.15)
				)
				(justify left bottom)
				(hide yes)
			)
		)
		(property "Author" "Antmicro"
			(at 149.86 171.45 0)
			(effects
				(font
					(size 1.27 1.27)
					(thickness 0.15)
				)
				(justify left bottom)
				(hide yes)
			)
		)
		(property "Val" "10k"
			(at 123.825 190.5 90)
			(effects
				(font
					(size 1.27 1.27)
					(thickness 0.15)
				)
				(justify right)
			)
		)
		(property "Tolerance" "1%"
			(at 132.08 171.45 0)
			(effects
				(font
					(size 1.27 1.27)
				)
				(justify left bottom)
				(hide yes)
			)
		)
		(pin "1"
		)
		(pin "2"
		)
		(instances
			(project "gmsl-deserializer"
				(path ""
					(reference "R49")
					(unit 1)
				)
			)
		)
	)
	(symbol
		(lib_id "antmicropower:GND")
		(at 223.52 104.14 0)
		(unit 1)
		(exclude_from_sim no)
		(in_bom yes)
		(on_board yes)
		(dnp no)
		(property "Reference" "#PWR076"
			(at 232.41 106.68 0)
			(effects
				(font
					(size 1.27 1.27)
					(thickness 0.15)
				)
				(justify left bottom)
				(hide yes)
			)
		)
		(property "Value" "GND"
			(at 223.52 107.95 0)
			(effects
				(font
					(size 1.27 1.27)
					(thickness 0.15)
				)
			)
		)
		(property "Footprint" ""
			(at 232.41 111.76 0)
			(effects
				(font
					(size 1.27 1.27)
					(thickness 0.15)
				)
				(justify left bottom)
				(hide yes)
			)
		)
		(property "Datasheet" ""
			(at 232.41 116.84 0)
			(effects
				(font
					(size 1.27 1.27)
					(thickness 0.15)
				)
				(justify left bottom)
				(hide yes)
			)
		)
		(property "Description" ""
			(at 223.52 104.14 0)
			(effects
				(font
					(size 1.27 1.27)
				)
				(hide yes)
			)
		)
		(property "Author" "Antmicro"
			(at 232.41 111.76 0)
			(effects
				(font
					(size 1.27 1.27)
					(thickness 0.15)
				)
				(justify left bottom)
				(hide yes)
			)
		)
		(property "License" "Apache-2.0"
			(at 232.41 114.3 0)
			(effects
				(font
					(size 1.27 1.27)
					(thickness 0.15)
				)
				(justify left bottom)
				(hide yes)
			)
		)
		(pin "1"
		)
		(instances
			(project "gmsl-deserializer"
				(path ""
					(reference "#PWR076")
					(unit 1)
				)
			)
		)
	)
	(symbol
		(lib_id "antmicroResistors0402:R_0R_0402")
		(at 91.44 177.8 270)
		(mirror x)
		(unit 1)
		(exclude_from_sim no)
		(in_bom yes)
		(on_board yes)
		(dnp no)
		(property "Reference" "R47"
			(at 95.885 175.26 0)
			(effects
				(font
					(size 1.27 1.27)
					(thickness 0.15)
				)
			)
		)
		(property "Value" "R_0R_0402"
			(at 78.74 157.48 0)
			(effects
				(font
					(size 1.27 1.27)
					(thickness 0.15)
				)
				(justify left bottom)
				(hide yes)
			)
		)
		(property "Footprint" "antmicro-footprints:R_0402_1005Metric"
			(at 76.2 157.48 0)
			(effects
				(font
					(size 1.27 1.27)
					(thickness 0.15)
				)
				(justify left bottom)
				(hide yes)
			)
		)
		(property "Datasheet" "https://industrial.panasonic.com/cdbs/www-data/pdf/RDA0000/AOA0000C301.pdf"
			(at 73.66 157.48 0)
			(effects
				(font
					(size 1.27 1.27)
					(thickness 0.15)
				)
				(justify left bottom)
				(hide yes)
			)
		)
		(property "Description" "SMD Chip Resistor, Jumper, 0 ohm, 100 mW, 0402 [1005 Metric], Thick Film, General Purpose"
			(at 91.44 177.8 0)
			(effects
				(font
					(size 1.27 1.27)
				)
				(hide yes)
			)
		)
		(property "MPN" "ERJ2GE0R00X"
			(at 71.12 157.48 0)
			(effects
				(font
					(size 1.27 1.27)
					(thickness 0.15)
				)
				(justify left bottom)
				(hide yes)
			)
		)
		(property "Manufacturer" "Panasonic"
			(at 68.58 157.48 0)
			(effects
				(font
					(size 1.27 1.27)
					(thickness 0.15)
				)
				(justify left bottom)
				(hide yes)
			)
		)
		(property "License" "Apache-2.0"
			(at 66.04 157.48 0)
			(effects
				(font
					(size 1.27 1.27)
					(thickness 0.15)
				)
				(justify left bottom)
				(hide yes)
			)
		)
		(property "Author" "Antmicro"
			(at 63.5 157.48 0)
			(effects
				(font
					(size 1.27 1.27)
					(thickness 0.15)
				)
				(justify left bottom)
				(hide yes)
			)
		)
		(property "Val" "0R"
			(at 93.98 175.26 0)
			(effects
				(font
					(size 1.27 1.27)
					(thickness 0.15)
				)
			)
		)
		(property "Tolerance" "~"
			(at 81.28 157.48 0)
			(effects
				(font
					(size 1.27 1.27)
				)
				(justify left bottom)
				(hide yes)
			)
		)
		(property "Current" "1A"
			(at 60.96 157.48 0)
			(effects
				(font
					(size 1.27 1.27)
					(thickness 0.15)
				)
				(justify left bottom)
				(hide yes)
			)
		)
		(pin "1"
		)
		(pin "2"
		)
		(instances
			(project "gmsl-deserializer"
				(path ""
					(reference "R47")
					(unit 1)
				)
			)
		)
	)
	(symbol
		(lib_id "antmicroCapacitors0402:C_100n_0402")
		(at 251.46 121.92 90)
		(unit 1)
		(exclude_from_sim no)
		(in_bom yes)
		(on_board yes)
		(dnp no)
		(property "Reference" "C46"
			(at 252.095 117.475 90)
			(effects
				(font
					(size 1.27 1.27)
					(thickness 0.15)
				)
				(justify right)
			)
		)
		(property "Value" "C_100n_0402"
			(at 261.62 101.6 0)
			(effects
				(font
					(size 1.27 1.27)
					(thickness 0.15)
				)
				(justify left bottom)
				(hide yes)
			)
		)
		(property "Footprint" "antmicro-footprints:C_0402_1005Metric"
			(at 264.16 101.6 0)
			(effects
				(font
					(size 1.27 1.27)
					(thickness 0.15)
				)
				(justify left bottom)
				(hide yes)
			)
		)
		(property "Datasheet" "https://www.murata.com/products/productdetail?partno=GRM155R61H104KE14%23"
			(at 266.7 101.6 0)
			(effects
				(font
					(size 1.27 1.27)
					(thickness 0.15)
				)
				(justify left bottom)
				(hide yes)
			)
		)
		(property "Description" "SMD Multilayer Ceramic Capacitor, 0.1 µF, 50 V, 0402 [1005 Metric], ± 10%, X5R, GRM Series"
			(at 251.46 121.92 0)
			(effects
				(font
					(size 1.27 1.27)
				)
				(hide yes)
			)
		)
		(property "MPN" "GRM155R61H104KE14D"
			(at 269.24 101.6 0)
			(effects
				(font
					(size 1.27 1.27)
					(thickness 0.15)
				)
				(justify left bottom)
				(hide yes)
			)
		)
		(property "Manufacturer" "Murata"
			(at 271.78 101.6 0)
			(effects
				(font
					(size 1.27 1.27)
					(thickness 0.15)
				)
				(justify left bottom)
				(hide yes)
			)
		)
		(property "License" "Apache-2.0"
			(at 274.32 101.6 0)
			(effects
				(font
					(size 1.27 1.27)
					(thickness 0.15)
				)
				(justify left bottom)
				(hide yes)
			)
		)
		(property "Author" "Antmicro"
			(at 276.86 101.6 0)
			(effects
				(font
					(size 1.27 1.27)
					(thickness 0.15)
				)
				(justify left bottom)
				(hide yes)
			)
		)
		(property "Val" "100n"
			(at 252.095 121.285 90)
			(effects
				(font
					(size 1.27 1.27)
					(thickness 0.15)
				)
				(justify right)
			)
		)
		(property "Voltage" "50V"
			(at 279.4 101.6 0)
			(effects
				(font
					(size 1.27 1.27)
				)
				(justify left bottom)
				(hide yes)
			)
		)
		(property "Dielectric" "X5R"
			(at 281.94 101.6 0)
			(effects
				(font
					(size 1.27 1.27)
				)
				(justify left bottom)
				(hide yes)
			)
		)
		(pin "1"
		)
		(pin "2"
		)
		(instances
			(project "gmsl-deserializer"
				(path ""
					(reference "C46")
					(unit 1)
				)
			)
		)
	)
	(symbol
		(lib_id "antmicropower:GND")
		(at 66.04 99.06 0)
		(unit 1)
		(exclude_from_sim no)
		(in_bom yes)
		(on_board yes)
		(dnp no)
		(property "Reference" "#PWR065"
			(at 74.93 101.6 0)
			(effects
				(font
					(size 1.27 1.27)
					(thickness 0.15)
				)
				(justify left bottom)
				(hide yes)
			)
		)
		(property "Value" "GND"
			(at 66.04 102.87 0)
			(effects
				(font
					(size 1.27 1.27)
					(thickness 0.15)
				)
			)
		)
		(property "Footprint" ""
			(at 74.93 106.68 0)
			(effects
				(font
					(size 1.27 1.27)
					(thickness 0.15)
				)
				(justify left bottom)
				(hide yes)
			)
		)
		(property "Datasheet" ""
			(at 74.93 111.76 0)
			(effects
				(font
					(size 1.27 1.27)
					(thickness 0.15)
				)
				(justify left bottom)
				(hide yes)
			)
		)
		(property "Description" ""
			(at 66.04 99.06 0)
			(effects
				(font
					(size 1.27 1.27)
				)
				(hide yes)
			)
		)
		(property "Author" "Antmicro"
			(at 74.93 106.68 0)
			(effects
				(font
					(size 1.27 1.27)
					(thickness 0.15)
				)
				(justify left bottom)
				(hide yes)
			)
		)
		(property "License" "Apache-2.0"
			(at 74.93 109.22 0)
			(effects
				(font
					(size 1.27 1.27)
					(thickness 0.15)
				)
				(justify left bottom)
				(hide yes)
			)
		)
		(pin "1"
		)
		(instances
			(project "gmsl-deserializer"
				(path ""
					(reference "#PWR065")
					(unit 1)
				)
			)
		)
	)
	(symbol
		(lib_id "antmicroCapacitors0402:C_10n_0402")
		(at 242.57 121.92 90)
		(unit 1)
		(exclude_from_sim no)
		(in_bom yes)
		(on_board yes)
		(dnp no)
		(property "Reference" "C43"
			(at 243.205 117.475 90)
			(effects
				(font
					(size 1.27 1.27)
					(thickness 0.15)
				)
				(justify right)
			)
		)
		(property "Value" "C_10n_0402"
			(at 252.73 101.6 0)
			(effects
				(font
					(size 1.27 1.27)
					(thickness 0.15)
				)
				(justify left bottom)
				(hide yes)
			)
		)
		(property "Footprint" "antmicro-footprints:C_0402_1005Metric"
			(at 255.27 101.6 0)
			(effects
				(font
					(size 1.27 1.27)
					(thickness 0.15)
				)
				(justify left bottom)
				(hide yes)
			)
		)
		(property "Datasheet" "https://www.murata.com/products/productdetail?partno=GRM155R71H103KA88%23"
			(at 257.81 101.6 0)
			(effects
				(font
					(size 1.27 1.27)
					(thickness 0.15)
				)
				(justify left bottom)
				(hide yes)
			)
		)
		(property "Description" "SMD Multilayer Ceramic Capacitor, 10000 pF, 50 V, 0402 [1005 Metric], ± 10%, X7R, GRM Series"
			(at 242.57 121.92 0)
			(effects
				(font
					(size 1.27 1.27)
				)
				(hide yes)
			)
		)
		(property "MPN" "GRM155R71H103KA88D"
			(at 260.35 101.6 0)
			(effects
				(font
					(size 1.27 1.27)
					(thickness 0.15)
				)
				(justify left bottom)
				(hide yes)
			)
		)
		(property "Manufacturer" "Murata"
			(at 262.89 101.6 0)
			(effects
				(font
					(size 1.27 1.27)
					(thickness 0.15)
				)
				(justify left bottom)
				(hide yes)
			)
		)
		(property "License" "Apache-2.0"
			(at 265.43 101.6 0)
			(effects
				(font
					(size 1.27 1.27)
					(thickness 0.15)
				)
				(justify left bottom)
				(hide yes)
			)
		)
		(property "Author" "Antmicro"
			(at 267.97 101.6 0)
			(effects
				(font
					(size 1.27 1.27)
					(thickness 0.15)
				)
				(justify left bottom)
				(hide yes)
			)
		)
		(property "Val" "10n"
			(at 243.205 121.285 90)
			(effects
				(font
					(size 1.27 1.27)
					(thickness 0.15)
				)
				(justify right)
			)
		)
		(property "Voltage" "50V"
			(at 270.51 101.6 0)
			(effects
				(font
					(size 1.27 1.27)
				)
				(justify left bottom)
				(hide yes)
			)
		)
		(property "Dielectric" "X7R"
			(at 273.05 101.6 0)
			(effects
				(font
					(size 1.27 1.27)
				)
				(justify left bottom)
				(hide yes)
			)
		)
		(pin "1"
		)
		(pin "2"
		)
		(instances
			(project "gmsl-deserializer"
				(path ""
					(reference "C43")
					(unit 1)
				)
			)
		)
	)
	(symbol
		(lib_id "antmicroCapacitors0402:C_100n_0402")
		(at 91.44 121.92 180)
		(unit 1)
		(exclude_from_sim no)
		(in_bom yes)
		(on_board yes)
		(dnp no)
		(property "Reference" "C35"
			(at 87.63 123.19 0)
			(effects
				(font
					(size 1.27 1.27)
					(thickness 0.15)
				)
				(justify left)
			)
		)
		(property "Value" "C_100n_0402"
			(at 71.12 111.76 0)
			(effects
				(font
					(size 1.27 1.27)
					(thickness 0.15)
				)
				(justify left bottom)
				(hide yes)
			)
		)
		(property "Footprint" "antmicro-footprints:C_0402_1005Metric"
			(at 71.12 109.22 0)
			(effects
				(font
					(size 1.27 1.27)
					(thickness 0.15)
				)
				(justify left bottom)
				(hide yes)
			)
		)
		(property "Datasheet" "https://www.murata.com/products/productdetail?partno=GRM155R61H104KE14%23"
			(at 71.12 106.68 0)
			(effects
				(font
					(size 1.27 1.27)
					(thickness 0.15)
				)
				(justify left bottom)
				(hide yes)
			)
		)
		(property "Description" "SMD Multilayer Ceramic Capacitor, 0.1 µF, 50 V, 0402 [1005 Metric], ± 10%, X5R, GRM Series"
			(at 91.44 121.92 0)
			(effects
				(font
					(size 1.27 1.27)
				)
				(hide yes)
			)
		)
		(property "MPN" "GRM155R61H104KE14D"
			(at 71.12 104.14 0)
			(effects
				(font
					(size 1.27 1.27)
					(thickness 0.15)
				)
				(justify left bottom)
				(hide yes)
			)
		)
		(property "Manufacturer" "Murata"
			(at 71.12 101.6 0)
			(effects
				(font
					(size 1.27 1.27)
					(thickness 0.15)
				)
				(justify left bottom)
				(hide yes)
			)
		)
		(property "License" "Apache-2.0"
			(at 71.12 99.06 0)
			(effects
				(font
					(size 1.27 1.27)
					(thickness 0.15)
				)
				(justify left bottom)
				(hide yes)
			)
		)
		(property "Author" "Antmicro"
			(at 71.12 96.52 0)
			(effects
				(font
					(size 1.27 1.27)
					(thickness 0.15)
				)
				(justify left bottom)
				(hide yes)
			)
		)
		(property "Val" "100n"
			(at 90.17 123.19 0)
			(effects
				(font
					(size 1.27 1.27)
					(thickness 0.15)
				)
				(justify right)
			)
		)
		(property "Voltage" "50V"
			(at 71.12 93.98 0)
			(effects
				(font
					(size 1.27 1.27)
				)
				(justify left bottom)
				(hide yes)
			)
		)
		(property "Dielectric" "X5R"
			(at 71.12 91.44 0)
			(effects
				(font
					(size 1.27 1.27)
				)
				(justify left bottom)
				(hide yes)
			)
		)
		(pin "1"
		)
		(pin "2"
		)
		(instances
			(project "gmsl-deserializer"
				(path ""
					(reference "C35")
					(unit 1)
				)
			)
		)
	)
	(symbol
		(lib_id "antmicroCapacitors0402:C_10u_0402")
		(at 243.84 200.66 90)
		(unit 1)
		(exclude_from_sim no)
		(in_bom yes)
		(on_board yes)
		(dnp no)
		(property "Reference" "C44"
			(at 244.475 196.215 90)
			(effects
				(font
					(size 1.27 1.27)
					(thickness 0.15)
				)
				(justify right)
			)
		)
		(property "Value" "C_10u_0402"
			(at 254 180.34 0)
			(effects
				(font
					(size 1.27 1.27)
					(thickness 0.15)
				)
				(justify left bottom)
				(hide yes)
			)
		)
		(property "Footprint" "antmicro-footprints:C_0402_1005Metric"
			(at 256.54 180.34 0)
			(effects
				(font
					(size 1.27 1.27)
					(thickness 0.15)
				)
				(justify left bottom)
				(hide yes)
			)
		)
		(property "Datasheet" "https://www.yageo.com/en/Chart/Download/pdf/CC0402MRX5R5BB106"
			(at 259.08 180.34 0)
			(effects
				(font
					(size 1.27 1.27)
					(thickness 0.15)
				)
				(justify left bottom)
				(hide yes)
			)
		)
		(property "Description" "SMD Multilayer Ceramic Capacitor, 10 µF, 6.3 V, 0402 [1005 Metric], ± 20%, X5R, CC Series"
			(at 243.84 200.66 0)
			(effects
				(font
					(size 1.27 1.27)
				)
				(hide yes)
			)
		)
		(property "MPN" "CC0402MRX5R5BB106"
			(at 261.62 180.34 0)
			(effects
				(font
					(size 1.27 1.27)
					(thickness 0.15)
				)
				(justify left bottom)
				(hide yes)
			)
		)
		(property "Manufacturer" "YAGEO"
			(at 264.16 180.34 0)
			(effects
				(font
					(size 1.27 1.27)
					(thickness 0.15)
				)
				(justify left bottom)
				(hide yes)
			)
		)
		(property "License" "Apache-2.0"
			(at 266.7 180.34 0)
			(effects
				(font
					(size 1.27 1.27)
					(thickness 0.15)
				)
				(justify left bottom)
				(hide yes)
			)
		)
		(property "Author" "Antmicro"
			(at 269.24 180.34 0)
			(effects
				(font
					(size 1.27 1.27)
					(thickness 0.15)
				)
				(justify left bottom)
				(hide yes)
			)
		)
		(property "Val" "10u"
			(at 244.475 200.025 90)
			(effects
				(font
					(size 1.27 1.27)
					(thickness 0.15)
				)
				(justify right)
			)
		)
		(property "Voltage" ""
			(at 271.78 180.34 0)
			(effects
				(font
					(size 1.27 1.27)
				)
				(justify left bottom)
				(hide yes)
			)
		)
		(property "Dielectric" ""
			(at 274.32 180.34 0)
			(effects
				(font
					(size 1.27 1.27)
				)
				(justify left bottom)
				(hide yes)
			)
		)
		(pin "1"
		)
		(pin "2"
		)
		(instances
			(project "gmsl-deserializer"
				(path ""
					(reference "C44")
					(unit 1)
				)
			)
		)
	)
	(symbol
		(lib_id "antmicroCapacitors0402:C_10u_0402")
		(at 223.52 102.87 90)
		(unit 1)
		(exclude_from_sim no)
		(in_bom yes)
		(on_board yes)
		(dnp no)
		(property "Reference" "C36"
			(at 224.155 98.425 90)
			(effects
				(font
					(size 1.27 1.27)
					(thickness 0.15)
				)
				(justify right)
			)
		)
		(property "Value" "C_10u_0402"
			(at 233.68 82.55 0)
			(effects
				(font
					(size 1.27 1.27)
					(thickness 0.15)
				)
				(justify left bottom)
				(hide yes)
			)
		)
		(property "Footprint" "antmicro-footprints:C_0402_1005Metric"
			(at 236.22 82.55 0)
			(effects
				(font
					(size 1.27 1.27)
					(thickness 0.15)
				)
				(justify left bottom)
				(hide yes)
			)
		)
		(property "Datasheet" "https://www.yageo.com/en/Chart/Download/pdf/CC0402MRX5R5BB106"
			(at 238.76 82.55 0)
			(effects
				(font
					(size 1.27 1.27)
					(thickness 0.15)
				)
				(justify left bottom)
				(hide yes)
			)
		)
		(property "Description" "SMD Multilayer Ceramic Capacitor, 10 µF, 6.3 V, 0402 [1005 Metric], ± 20%, X5R, CC Series"
			(at 223.52 102.87 0)
			(effects
				(font
					(size 1.27 1.27)
				)
				(hide yes)
			)
		)
		(property "MPN" "CC0402MRX5R5BB106"
			(at 241.3 82.55 0)
			(effects
				(font
					(size 1.27 1.27)
					(thickness 0.15)
				)
				(justify left bottom)
				(hide yes)
			)
		)
		(property "Manufacturer" "YAGEO"
			(at 243.84 82.55 0)
			(effects
				(font
					(size 1.27 1.27)
					(thickness 0.15)
				)
				(justify left bottom)
				(hide yes)
			)
		)
		(property "License" "Apache-2.0"
			(at 246.38 82.55 0)
			(effects
				(font
					(size 1.27 1.27)
					(thickness 0.15)
				)
				(justify left bottom)
				(hide yes)
			)
		)
		(property "Author" "Antmicro"
			(at 248.92 82.55 0)
			(effects
				(font
					(size 1.27 1.27)
					(thickness 0.15)
				)
				(justify left bottom)
				(hide yes)
			)
		)
		(property "Val" "10u"
			(at 224.155 102.235 90)
			(effects
				(font
					(size 1.27 1.27)
					(thickness 0.15)
				)
				(justify right)
			)
		)
		(property "Voltage" ""
			(at 251.46 82.55 0)
			(effects
				(font
					(size 1.27 1.27)
				)
				(justify left bottom)
				(hide yes)
			)
		)
		(property "Dielectric" ""
			(at 254 82.55 0)
			(effects
				(font
					(size 1.27 1.27)
				)
				(justify left bottom)
				(hide yes)
			)
		)
		(pin "1"
		)
		(pin "2"
		)
		(instances
			(project "gmsl-deserializer"
				(path ""
					(reference "C36")
					(unit 1)
				)
			)
		)
	)
	(symbol
		(lib_id "antmicroCapacitors0402:C_10n_0402")
		(at 261.62 121.92 90)
		(unit 1)
		(exclude_from_sim no)
		(in_bom yes)
		(on_board yes)
		(dnp no)
		(property "Reference" "C49"
			(at 262.255 117.475 90)
			(effects
				(font
					(size 1.27 1.27)
					(thickness 0.15)
				)
				(justify right)
			)
		)
		(property "Value" "C_10n_0402"
			(at 271.78 101.6 0)
			(effects
				(font
					(size 1.27 1.27)
					(thickness 0.15)
				)
				(justify left bottom)
				(hide yes)
			)
		)
		(property "Footprint" "antmicro-footprints:C_0402_1005Metric"
			(at 274.32 101.6 0)
			(effects
				(font
					(size 1.27 1.27)
					(thickness 0.15)
				)
				(justify left bottom)
				(hide yes)
			)
		)
		(property "Datasheet" "https://www.murata.com/products/productdetail?partno=GRM155R71H103KA88%23"
			(at 276.86 101.6 0)
			(effects
				(font
					(size 1.27 1.27)
					(thickness 0.15)
				)
				(justify left bottom)
				(hide yes)
			)
		)
		(property "Description" "SMD Multilayer Ceramic Capacitor, 10000 pF, 50 V, 0402 [1005 Metric], ± 10%, X7R, GRM Series"
			(at 261.62 121.92 0)
			(effects
				(font
					(size 1.27 1.27)
				)
				(hide yes)
			)
		)
		(property "MPN" "GRM155R71H103KA88D"
			(at 279.4 101.6 0)
			(effects
				(font
					(size 1.27 1.27)
					(thickness 0.15)
				)
				(justify left bottom)
				(hide yes)
			)
		)
		(property "Manufacturer" "Murata"
			(at 281.94 101.6 0)
			(effects
				(font
					(size 1.27 1.27)
					(thickness 0.15)
				)
				(justify left bottom)
				(hide yes)
			)
		)
		(property "License" "Apache-2.0"
			(at 284.48 101.6 0)
			(effects
				(font
					(size 1.27 1.27)
					(thickness 0.15)
				)
				(justify left bottom)
				(hide yes)
			)
		)
		(property "Author" "Antmicro"
			(at 287.02 101.6 0)
			(effects
				(font
					(size 1.27 1.27)
					(thickness 0.15)
				)
				(justify left bottom)
				(hide yes)
			)
		)
		(property "Val" "10n"
			(at 262.255 121.285 90)
			(effects
				(font
					(size 1.27 1.27)
					(thickness 0.15)
				)
				(justify right)
			)
		)
		(property "Voltage" "50V"
			(at 289.56 101.6 0)
			(effects
				(font
					(size 1.27 1.27)
				)
				(justify left bottom)
				(hide yes)
			)
		)
		(property "Dielectric" "X7R"
			(at 292.1 101.6 0)
			(effects
				(font
					(size 1.27 1.27)
				)
				(justify left bottom)
				(hide yes)
			)
		)
		(pin "1"
		)
		(pin "2"
		)
		(instances
			(project "gmsl-deserializer"
				(path ""
					(reference "C49")
					(unit 1)
				)
			)
		)
	)
	(symbol
		(lib_id "antmicroResistors0402:R_10k_0402")
		(at 162.56 191.77 90)
		(unit 1)
		(exclude_from_sim no)
		(in_bom yes)
		(on_board yes)
		(dnp no)
		(property "Reference" "R51"
			(at 164.465 187.96 90)
			(effects
				(font
					(size 1.27 1.27)
					(thickness 0.15)
				)
				(justify right)
			)
		)
		(property "Value" "R_10k_0402"
			(at 175.26 171.45 0)
			(effects
				(font
					(size 1.27 1.27)
					(thickness 0.15)
				)
				(justify left bottom)
				(hide yes)
			)
		)
		(property "Footprint" "antmicro-footprints:R_0402_1005Metric"
			(at 177.8 171.45 0)
			(effects
				(font
					(size 1.27 1.27)
					(thickness 0.15)
				)
				(justify left bottom)
				(hide yes)
			)
		)
		(property "Datasheet" "https://www.bourns.com/docs/product-datasheets/cr.pdf"
			(at 180.34 171.45 0)
			(effects
				(font
					(size 1.27 1.27)
					(thickness 0.15)
				)
				(justify left bottom)
				(hide yes)
			)
		)
		(property "Description" "SMD Chip Resistor, 10 kohm, ± 1%, 62.5 mW, 0402 [1005 Metric], Thick Film, General Purpose"
			(at 162.56 191.77 0)
			(effects
				(font
					(size 1.27 1.27)
				)
				(hide yes)
			)
		)
		(property "MPN" "CR0402-FX-1002GLF"
			(at 182.88 171.45 0)
			(effects
				(font
					(size 1.27 1.27)
					(thickness 0.15)
				)
				(justify left bottom)
				(hide yes)
			)
		)
		(property "Manufacturer" "Bourns"
			(at 185.42 171.45 0)
			(effects
				(font
					(size 1.27 1.27)
					(thickness 0.15)
				)
				(justify left bottom)
				(hide yes)
			)
		)
		(property "License" "Apache-2.0"
			(at 187.96 171.45 0)
			(effects
				(font
					(size 1.27 1.27)
					(thickness 0.15)
				)
				(justify left bottom)
				(hide yes)
			)
		)
		(property "Author" "Antmicro"
			(at 190.5 171.45 0)
			(effects
				(font
					(size 1.27 1.27)
					(thickness 0.15)
				)
				(justify left bottom)
				(hide yes)
			)
		)
		(property "Val" "10k"
			(at 164.465 190.5 90)
			(effects
				(font
					(size 1.27 1.27)
					(thickness 0.15)
				)
				(justify right)
			)
		)
		(property "Tolerance" "1%"
			(at 172.72 171.45 0)
			(effects
				(font
					(size 1.27 1.27)
				)
				(justify left bottom)
				(hide yes)
			)
		)
		(pin "1"
		)
		(pin "2"
		)
		(instances
			(project "gmsl-deserializer"
				(path ""
					(reference "R51")
					(unit 1)
				)
			)
		)
	)
	(symbol
		(lib_id "antmicroCapacitors0402:C_100n_0402")
		(at 351.79 102.87 90)
		(unit 1)
		(exclude_from_sim no)
		(in_bom yes)
		(on_board yes)
		(dnp no)
		(property "Reference" "C52"
			(at 352.425 98.425 90)
			(effects
				(font
					(size 1.27 1.27)
					(thickness 0.15)
				)
				(justify right)
			)
		)
		(property "Value" "C_100n_0402"
			(at 361.95 82.55 0)
			(effects
				(font
					(size 1.27 1.27)
					(thickness 0.15)
				)
				(justify left bottom)
				(hide yes)
			)
		)
		(property "Footprint" "antmicro-footprints:C_0402_1005Metric"
			(at 364.49 82.55 0)
			(effects
				(font
					(size 1.27 1.27)
					(thickness 0.15)
				)
				(justify left bottom)
				(hide yes)
			)
		)
		(property "Datasheet" "https://www.murata.com/products/productdetail?partno=GRM155R61H104KE14%23"
			(at 367.03 82.55 0)
			(effects
				(font
					(size 1.27 1.27)
					(thickness 0.15)
				)
				(justify left bottom)
				(hide yes)
			)
		)
		(property "Description" "SMD Multilayer Ceramic Capacitor, 0.1 µF, 50 V, 0402 [1005 Metric], ± 10%, X5R, GRM Series"
			(at 351.79 102.87 0)
			(effects
				(font
					(size 1.27 1.27)
				)
				(hide yes)
			)
		)
		(property "MPN" "GRM155R61H104KE14D"
			(at 369.57 82.55 0)
			(effects
				(font
					(size 1.27 1.27)
					(thickness 0.15)
				)
				(justify left bottom)
				(hide yes)
			)
		)
		(property "Manufacturer" "Murata"
			(at 372.11 82.55 0)
			(effects
				(font
					(size 1.27 1.27)
					(thickness 0.15)
				)
				(justify left bottom)
				(hide yes)
			)
		)
		(property "License" "Apache-2.0"
			(at 374.65 82.55 0)
			(effects
				(font
					(size 1.27 1.27)
					(thickness 0.15)
				)
				(justify left bottom)
				(hide yes)
			)
		)
		(property "Author" "Antmicro"
			(at 377.19 82.55 0)
			(effects
				(font
					(size 1.27 1.27)
					(thickness 0.15)
				)
				(justify left bottom)
				(hide yes)
			)
		)
		(property "Val" "100n"
			(at 352.425 102.235 90)
			(effects
				(font
					(size 1.27 1.27)
					(thickness 0.15)
				)
				(justify right)
			)
		)
		(property "Voltage" "50V"
			(at 379.73 82.55 0)
			(effects
				(font
					(size 1.27 1.27)
				)
				(justify left bottom)
				(hide yes)
			)
		)
		(property "Dielectric" "X5R"
			(at 382.27 82.55 0)
			(effects
				(font
					(size 1.27 1.27)
				)
				(justify left bottom)
				(hide yes)
			)
		)
		(pin "1"
		)
		(pin "2"
		)
		(instances
			(project "gmsl-deserializer"
				(path ""
					(reference "C52")
					(unit 1)
				)
			)
		)
	)
	(symbol
		(lib_id "antmicroCapacitors0402:C_10u_0402")
		(at 360.68 102.87 90)
		(unit 1)
		(exclude_from_sim no)
		(in_bom yes)
		(on_board yes)
		(dnp no)
		(property "Reference" "C54"
			(at 361.315 98.425 90)
			(effects
				(font
					(size 1.27 1.27)
					(thickness 0.15)
				)
				(justify right)
			)
		)
		(property "Value" "C_10u_0402"
			(at 370.84 82.55 0)
			(effects
				(font
					(size 1.27 1.27)
					(thickness 0.15)
				)
				(justify left bottom)
				(hide yes)
			)
		)
		(property "Footprint" "antmicro-footprints:C_0402_1005Metric"
			(at 373.38 82.55 0)
			(effects
				(font
					(size 1.27 1.27)
					(thickness 0.15)
				)
				(justify left bottom)
				(hide yes)
			)
		)
		(property "Datasheet" "https://www.yageo.com/en/Chart/Download/pdf/CC0402MRX5R5BB106"
			(at 375.92 82.55 0)
			(effects
				(font
					(size 1.27 1.27)
					(thickness 0.15)
				)
				(justify left bottom)
				(hide yes)
			)
		)
		(property "Description" "SMD Multilayer Ceramic Capacitor, 10 µF, 6.3 V, 0402 [1005 Metric], ± 20%, X5R, CC Series"
			(at 360.68 102.87 0)
			(effects
				(font
					(size 1.27 1.27)
				)
				(hide yes)
			)
		)
		(property "MPN" "CC0402MRX5R5BB106"
			(at 378.46 82.55 0)
			(effects
				(font
					(size 1.27 1.27)
					(thickness 0.15)
				)
				(justify left bottom)
				(hide yes)
			)
		)
		(property "Manufacturer" "YAGEO"
			(at 381 82.55 0)
			(effects
				(font
					(size 1.27 1.27)
					(thickness 0.15)
				)
				(justify left bottom)
				(hide yes)
			)
		)
		(property "License" "Apache-2.0"
			(at 383.54 82.55 0)
			(effects
				(font
					(size 1.27 1.27)
					(thickness 0.15)
				)
				(justify left bottom)
				(hide yes)
			)
		)
		(property "Author" "Antmicro"
			(at 386.08 82.55 0)
			(effects
				(font
					(size 1.27 1.27)
					(thickness 0.15)
				)
				(justify left bottom)
				(hide yes)
			)
		)
		(property "Val" "10u"
			(at 361.315 102.235 90)
			(effects
				(font
					(size 1.27 1.27)
					(thickness 0.15)
				)
				(justify right)
			)
		)
		(property "Voltage" ""
			(at 388.62 82.55 0)
			(effects
				(font
					(size 1.27 1.27)
				)
				(justify left bottom)
				(hide yes)
			)
		)
		(property "Dielectric" ""
			(at 391.16 82.55 0)
			(effects
				(font
					(size 1.27 1.27)
				)
				(justify left bottom)
				(hide yes)
			)
		)
		(pin "1"
		)
		(pin "2"
		)
		(instances
			(project "gmsl-deserializer"
				(path ""
					(reference "C54")
					(unit 1)
				)
			)
		)
	)
	(symbol
		(lib_id "antmicroResistors0402:R_10k_0402")
		(at 326.39 110.49 90)
		(unit 1)
		(exclude_from_sim no)
		(in_bom yes)
		(on_board yes)
		(dnp no)
		(property "Reference" "R55"
			(at 328.295 106.68 90)
			(effects
				(font
					(size 1.27 1.27)
					(thickness 0.15)
				)
				(justify right)
			)
		)
		(property "Value" "R_10k_0402"
			(at 339.09 90.17 0)
			(effects
				(font
					(size 1.27 1.27)
					(thickness 0.15)
				)
				(justify left bottom)
				(hide yes)
			)
		)
		(property "Footprint" "antmicro-footprints:R_0402_1005Metric"
			(at 341.63 90.17 0)
			(effects
				(font
					(size 1.27 1.27)
					(thickness 0.15)
				)
				(justify left bottom)
				(hide yes)
			)
		)
		(property "Datasheet" "https://www.bourns.com/docs/product-datasheets/cr.pdf"
			(at 344.17 90.17 0)
			(effects
				(font
					(size 1.27 1.27)
					(thickness 0.15)
				)
				(justify left bottom)
				(hide yes)
			)
		)
		(property "Description" "SMD Chip Resistor, 10 kohm, ± 1%, 62.5 mW, 0402 [1005 Metric], Thick Film, General Purpose"
			(at 326.39 110.49 0)
			(effects
				(font
					(size 1.27 1.27)
				)
				(hide yes)
			)
		)
		(property "MPN" "CR0402-FX-1002GLF"
			(at 346.71 90.17 0)
			(effects
				(font
					(size 1.27 1.27)
					(thickness 0.15)
				)
				(justify left bottom)
				(hide yes)
			)
		)
		(property "Manufacturer" "Bourns"
			(at 349.25 90.17 0)
			(effects
				(font
					(size 1.27 1.27)
					(thickness 0.15)
				)
				(justify left bottom)
				(hide yes)
			)
		)
		(property "License" "Apache-2.0"
			(at 351.79 90.17 0)
			(effects
				(font
					(size 1.27 1.27)
					(thickness 0.15)
				)
				(justify left bottom)
				(hide yes)
			)
		)
		(property "Author" "Antmicro"
			(at 354.33 90.17 0)
			(effects
				(font
					(size 1.27 1.27)
					(thickness 0.15)
				)
				(justify left bottom)
				(hide yes)
			)
		)
		(property "Val" "10k"
			(at 328.295 109.22 90)
			(effects
				(font
					(size 1.27 1.27)
					(thickness 0.15)
				)
				(justify right)
			)
		)
		(property "Tolerance" "1%"
			(at 336.55 90.17 0)
			(effects
				(font
					(size 1.27 1.27)
				)
				(justify left bottom)
				(hide yes)
			)
		)
		(pin "1"
		)
		(pin "2"
		)
		(instances
			(project "gmsl-deserializer"
				(path ""
					(reference "R55")
					(unit 1)
				)
			)
		)
	)
	(symbol
		(lib_id "antmicropower:GND")
		(at 121.92 193.04 0)
		(unit 1)
		(exclude_from_sim no)
		(in_bom yes)
		(on_board yes)
		(dnp no)
		(property "Reference" "#PWR072"
			(at 130.81 195.58 0)
			(effects
				(font
					(size 1.27 1.27)
					(thickness 0.15)
				)
				(justify left bottom)
				(hide yes)
			)
		)
		(property "Value" "GND"
			(at 121.92 196.85 0)
			(effects
				(font
					(size 1.27 1.27)
					(thickness 0.15)
				)
			)
		)
		(property "Footprint" ""
			(at 130.81 200.66 0)
			(effects
				(font
					(size 1.27 1.27)
					(thickness 0.15)
				)
				(justify left bottom)
				(hide yes)
			)
		)
		(property "Datasheet" ""
			(at 130.81 205.74 0)
			(effects
				(font
					(size 1.27 1.27)
					(thickness 0.15)
				)
				(justify left bottom)
				(hide yes)
			)
		)
		(property "Description" ""
			(at 121.92 193.04 0)
			(effects
				(font
					(size 1.27 1.27)
				)
				(hide yes)
			)
		)
		(property "Author" "Antmicro"
			(at 130.81 200.66 0)
			(effects
				(font
					(size 1.27 1.27)
					(thickness 0.15)
				)
				(justify left bottom)
				(hide yes)
			)
		)
		(property "License" "Apache-2.0"
			(at 130.81 203.2 0)
			(effects
				(font
					(size 1.27 1.27)
					(thickness 0.15)
				)
				(justify left bottom)
				(hide yes)
			)
		)
		(pin "1"
		)
		(instances
			(project "gmsl-deserializer"
				(path ""
					(reference "#PWR072")
					(unit 1)
				)
			)
		)
	)
	(symbol
		(lib_id "antmicroTVSDiodes:PESD4USB5U-TTS")
		(at 107.95 127 270)
		(unit 1)
		(exclude_from_sim no)
		(in_bom yes)
		(on_board yes)
		(dnp no)
		(property "Reference" "D4"
			(at 95.885 135.89 90)
			(effects
				(font
					(size 1.27 1.27)
					(thickness 0.15)
				)
				(justify left)
			)
		)
		(property "Value" "PESD4USB5U-TTS"
			(at 95.885 137.795 90)
			(effects
				(font
					(size 1.27 1.27)
					(thickness 0.15)
				)
				(justify left)
			)
		)
		(property "Footprint" "antmicro-footprints:DFN-10_2.5x1mm"
			(at 93.98 126.365 0)
			(effects
				(font
					(size 1.27 1.27)
					(thickness 0.15)
				)
				(justify left bottom)
				(hide yes)
			)
		)
		(property "Datasheet" "https://assets.nexperia.com/documents/data-sheet/PESD4USB5U-TTS.pdf"
			(at 93.98 123.825 0)
			(effects
				(font
					(size 1.27 1.27)
					(thickness 0.15)
				)
				(justify left bottom)
				(hide yes)
			)
		)
		(property "Description" "TVS diode array, 15kV, DFN-10, 5 V, 0.5 pF"
			(at 107.95 127 0)
			(effects
				(font
					(size 1.27 1.27)
				)
				(hide yes)
			)
		)
		(property "MPN" "PESD4USB5U-TTS"
			(at 93.98 121.285 0)
			(effects
				(font
					(size 1.27 1.27)
					(thickness 0.15)
				)
				(justify left bottom)
				(hide yes)
			)
		)
		(property "Manufacturer" "Nexperia"
			(at 93.98 118.745 0)
			(effects
				(font
					(size 1.27 1.27)
					(thickness 0.15)
				)
				(justify left bottom)
				(hide yes)
			)
		)
		(property "Author" "Antmicro"
			(at 93.98 116.205 0)
			(effects
				(font
					(size 1.27 1.27)
					(thickness 0.15)
				)
				(justify left bottom)
				(hide yes)
			)
		)
		(property "License" "Apache-2.0"
			(at 93.98 113.665 0)
			(effects
				(font
					(size 1.27 1.27)
					(thickness 0.15)
				)
				(justify left bottom)
				(hide yes)
			)
		)
		(pin "1"
		)
		(pin "10"
		)
		(pin "2"
		)
		(pin "3"
		)
		(pin "4"
		)
		(pin "5"
		)
		(pin "6"
		)
		(pin "7"
		)
		(pin "8"
		)
		(pin "9"
		)
		(instances
			(project "gmsl-deserializer"
				(path ""
					(reference "D4")
					(unit 1)
				)
			)
		)
	)
	(symbol
		(lib_id "antmicroCapacitors0402:C_33p_0402")
		(at 91.44 187.96 90)
		(unit 1)
		(exclude_from_sim no)
		(in_bom yes)
		(on_board yes)
		(dnp no)
		(property "Reference" "C57"
			(at 93.345 184.15 90)
			(effects
				(font
					(size 1.27 1.27)
					(thickness 0.15)
				)
				(justify right)
			)
		)
		(property "Value" "C_33p_0402"
			(at 101.6 167.64 0)
			(effects
				(font
					(size 1.27 1.27)
					(thickness 0.15)
				)
				(justify left bottom)
				(hide yes)
			)
		)
		(property "Footprint" "antmicro-footprints:C_0402_1005Metric"
			(at 104.14 167.64 0)
			(effects
				(font
					(size 1.27 1.27)
					(thickness 0.15)
				)
				(justify left bottom)
				(hide yes)
			)
		)
		(property "Datasheet" "https://spicat.kyocera-avx.com/product/mlcc/chartview/04025A330FAT2A/"
			(at 106.68 167.64 0)
			(effects
				(font
					(size 1.27 1.27)
					(thickness 0.15)
				)
				(justify left bottom)
				(hide yes)
			)
		)
		(property "Description" "SMD Multilayer Ceramic Capacitor, 33 pF, 50 V, 0402 [1005 Metric], ± 5%, C0G / NP0, MC"
			(at 91.44 187.96 0)
			(effects
				(font
					(size 1.27 1.27)
				)
				(hide yes)
			)
		)
		(property "MPN" "04025A330FAT2A"
			(at 109.22 167.64 0)
			(effects
				(font
					(size 1.27 1.27)
					(thickness 0.15)
				)
				(justify left bottom)
				(hide yes)
			)
		)
		(property "Manufacturer" "KYOCERA AVX"
			(at 111.76 167.64 0)
			(effects
				(font
					(size 1.27 1.27)
					(thickness 0.15)
				)
				(justify left bottom)
				(hide yes)
			)
		)
		(property "License" "Apache-2.0"
			(at 114.3 167.64 0)
			(effects
				(font
					(size 1.27 1.27)
					(thickness 0.15)
				)
				(justify left bottom)
				(hide yes)
			)
		)
		(property "Author" "Antmicro"
			(at 116.84 167.64 0)
			(effects
				(font
					(size 1.27 1.27)
					(thickness 0.15)
				)
				(justify left bottom)
				(hide yes)
			)
		)
		(property "Val" "33p"
			(at 93.98 186.69 90)
			(effects
				(font
					(size 1.27 1.27)
					(thickness 0.15)
				)
				(justify right)
			)
		)
		(property "Voltage" ""
			(at 119.38 167.64 0)
			(effects
				(font
					(size 1.27 1.27)
				)
				(justify left bottom)
				(hide yes)
			)
		)
		(property "Dielectric" ""
			(at 121.92 167.64 0)
			(effects
				(font
					(size 1.27 1.27)
				)
				(justify left bottom)
				(hide yes)
			)
		)
		(pin "1"
		)
		(pin "2"
		)
		(instances
			(project "gmsl-deserializer"
				(path ""
					(reference "C57")
					(unit 1)
				)
			)
		)
	)
	(symbol
		(lib_id "antmicroInterfaceControllers:MAX96724GTN_VY+")
		(at 280.67 113.03 0)
		(unit 1)
		(exclude_from_sim no)
		(in_bom yes)
		(on_board yes)
		(dnp no)
		(fields_autoplaced yes)
		(property "Reference" "U7"
			(at 298.45 105.41 0)
			(effects
				(font
					(size 1.27 1.27)
					(thickness 0.15)
				)
			)
		)
		(property "Value" "MAX96724GTN_VY+"
			(at 331.47 120.65 0)
			(effects
				(font
					(size 1.27 1.27)
					(thickness 0.15)
				)
				(justify left bottom)
				(hide yes)
			)
		)
		(property "Footprint" "antmicro-footprints:QFN-56-1EP_8x8mm_P0.5mm_EP4.8x4.8mm"
			(at 331.47 123.19 0)
			(effects
				(font
					(size 1.27 1.27)
					(thickness 0.15)
				)
				(justify left bottom)
				(hide yes)
			)
		)
		(property "Datasheet" "https://www.mouser.com/datasheet/2/609/max96724-3135154.pdf"
			(at 331.47 125.73 0)
			(effects
				(font
					(size 1.27 1.27)
					(thickness 0.15)
				)
				(justify left bottom)
				(hide yes)
			)
		)
		(property "Description" "ADI GMSL2/1 Tunneling Quad Deserializer 6GHz with 2x4 or 4x2 MIPI DPHY/CPHY Outputs"
			(at 280.67 113.03 0)
			(effects
				(font
					(size 1.27 1.27)
				)
				(hide yes)
			)
		)
		(property "MPN" "MAX96724GTN/VY+"
			(at 298.45 107.95 0)
			(effects
				(font
					(size 1.27 1.27)
					(thickness 0.15)
				)
			)
		)
		(property "Manufacturer" "Analog Devices"
			(at 331.47 128.27 0)
			(effects
				(font
					(size 1.27 1.27)
					(thickness 0.15)
				)
				(justify left bottom)
				(hide yes)
			)
		)
		(property "Author" "Antmicro"
			(at 331.47 130.81 0)
			(effects
				(font
					(size 1.27 1.27)
					(thickness 0.15)
				)
				(justify left bottom)
				(hide yes)
			)
		)
		(property "License" "Apache-2.0"
			(at 331.47 133.35 0)
			(effects
				(font
					(size 1.27 1.27)
					(thickness 0.15)
				)
				(justify left bottom)
				(hide yes)
			)
		)
		(pin "1"
		)
		(pin "10"
		)
		(pin "11"
		)
		(pin "12"
		)
		(pin "13"
		)
		(pin "14"
		)
		(pin "15"
		)
		(pin "16"
		)
		(pin "17"
		)
		(pin "18"
		)
		(pin "19"
		)
		(pin "2"
		)
		(pin "20"
		)
		(pin "21"
		)
		(pin "22"
		)
		(pin "23"
		)
		(pin "24"
		)
		(pin "25"
		)
		(pin "26"
		)
		(pin "27"
		)
		(pin "28"
		)
		(pin "29"
		)
		(pin "3"
		)
		(pin "30"
		)
		(pin "31"
		)
		(pin "32"
		)
		(pin "33"
		)
		(pin "34"
		)
		(pin "35"
		)
		(pin "36"
		)
		(pin "37"
		)
		(pin "38"
		)
		(pin "39"
		)
		(pin "4"
		)
		(pin "40"
		)
		(pin "41"
		)
		(pin "42"
		)
		(pin "43"
		)
		(pin "44"
		)
		(pin "45"
		)
		(pin "46"
		)
		(pin "47"
		)
		(pin "48"
		)
		(pin "49"
		)
		(pin "5"
		)
		(pin "50"
		)
		(pin "51"
		)
		(pin "52"
		)
		(pin "53"
		)
		(pin "54"
		)
		(pin "55"
		)
		(pin "56"
		)
		(pin "57"
		)
		(pin "6"
		)
		(pin "7"
		)
		(pin "8"
		)
		(pin "9"
		)
		(instances
			(project "gmsl-deserializer"
				(path ""
					(reference "U7")
					(unit 1)
				)
			)
		)
	)
	(symbol
		(lib_id "antmicroCapacitors0402:C_100n_0402")
		(at 236.22 200.66 90)
		(unit 1)
		(exclude_from_sim no)
		(in_bom yes)
		(on_board yes)
		(dnp no)
		(property "Reference" "C41"
			(at 236.855 196.215 90)
			(effects
				(font
					(size 1.27 1.27)
					(thickness 0.15)
				)
				(justify right)
			)
		)
		(property "Value" "C_100n_0402"
			(at 246.38 180.34 0)
			(effects
				(font
					(size 1.27 1.27)
					(thickness 0.15)
				)
				(justify left bottom)
				(hide yes)
			)
		)
		(property "Footprint" "antmicro-footprints:C_0402_1005Metric"
			(at 248.92 180.34 0)
			(effects
				(font
					(size 1.27 1.27)
					(thickness 0.15)
				)
				(justify left bottom)
				(hide yes)
			)
		)
		(property "Datasheet" "https://www.murata.com/products/productdetail?partno=GRM155R61H104KE14%23"
			(at 251.46 180.34 0)
			(effects
				(font
					(size 1.27 1.27)
					(thickness 0.15)
				)
				(justify left bottom)
				(hide yes)
			)
		)
		(property "Description" "SMD Multilayer Ceramic Capacitor, 0.1 µF, 50 V, 0402 [1005 Metric], ± 10%, X5R, GRM Series"
			(at 236.22 200.66 0)
			(effects
				(font
					(size 1.27 1.27)
				)
				(hide yes)
			)
		)
		(property "MPN" "GRM155R61H104KE14D"
			(at 254 180.34 0)
			(effects
				(font
					(size 1.27 1.27)
					(thickness 0.15)
				)
				(justify left bottom)
				(hide yes)
			)
		)
		(property "Manufacturer" "Murata"
			(at 256.54 180.34 0)
			(effects
				(font
					(size 1.27 1.27)
					(thickness 0.15)
				)
				(justify left bottom)
				(hide yes)
			)
		)
		(property "License" "Apache-2.0"
			(at 259.08 180.34 0)
			(effects
				(font
					(size 1.27 1.27)
					(thickness 0.15)
				)
				(justify left bottom)
				(hide yes)
			)
		)
		(property "Author" "Antmicro"
			(at 261.62 180.34 0)
			(effects
				(font
					(size 1.27 1.27)
					(thickness 0.15)
				)
				(justify left bottom)
				(hide yes)
			)
		)
		(property "Val" "100n"
			(at 236.855 200.025 90)
			(effects
				(font
					(size 1.27 1.27)
					(thickness 0.15)
				)
				(justify right)
			)
		)
		(property "Voltage" "50V"
			(at 264.16 180.34 0)
			(effects
				(font
					(size 1.27 1.27)
				)
				(justify left bottom)
				(hide yes)
			)
		)
		(property "Dielectric" "X5R"
			(at 266.7 180.34 0)
			(effects
				(font
					(size 1.27 1.27)
				)
				(justify left bottom)
				(hide yes)
			)
		)
		(pin "1"
		)
		(pin "2"
		)
		(instances
			(project "gmsl-deserializer"
				(path ""
					(reference "C41")
					(unit 1)
				)
			)
		)
	)
	(symbol
		(lib_id "antmicropower:GND")
		(at 351.79 104.14 0)
		(mirror y)
		(unit 1)
		(exclude_from_sim no)
		(in_bom yes)
		(on_board yes)
		(dnp no)
		(property "Reference" "#PWR094"
			(at 342.9 106.68 0)
			(effects
				(font
					(size 1.27 1.27)
					(thickness 0.15)
				)
				(justify left bottom)
				(hide yes)
			)
		)
		(property "Value" "GND"
			(at 351.79 107.95 0)
			(effects
				(font
					(size 1.27 1.27)
					(thickness 0.15)
				)
			)
		)
		(property "Footprint" ""
			(at 342.9 111.76 0)
			(effects
				(font
					(size 1.27 1.27)
					(thickness 0.15)
				)
				(justify left bottom)
				(hide yes)
			)
		)
		(property "Datasheet" ""
			(at 342.9 116.84 0)
			(effects
				(font
					(size 1.27 1.27)
					(thickness 0.15)
				)
				(justify left bottom)
				(hide yes)
			)
		)
		(property "Description" ""
			(at 351.79 104.14 0)
			(effects
				(font
					(size 1.27 1.27)
				)
				(hide yes)
			)
		)
		(property "Author" "Antmicro"
			(at 342.9 111.76 0)
			(effects
				(font
					(size 1.27 1.27)
					(thickness 0.15)
				)
				(justify left bottom)
				(hide yes)
			)
		)
		(property "License" "Apache-2.0"
			(at 342.9 114.3 0)
			(effects
				(font
					(size 1.27 1.27)
					(thickness 0.15)
				)
				(justify left bottom)
				(hide yes)
			)
		)
		(pin "1"
		)
		(instances
			(project "gmsl-deserializer"
				(path ""
					(reference "#PWR094")
					(unit 1)
				)
			)
		)
	)
	(symbol
		(lib_id "antmicroCapacitors0402:C_100n_0402")
		(at 232.41 102.87 90)
		(unit 1)
		(exclude_from_sim no)
		(in_bom yes)
		(on_board yes)
		(dnp no)
		(property "Reference" "C39"
			(at 233.045 98.425 90)
			(effects
				(font
					(size 1.27 1.27)
					(thickness 0.15)
				)
				(justify right)
			)
		)
		(property "Value" "C_100n_0402"
			(at 242.57 82.55 0)
			(effects
				(font
					(size 1.27 1.27)
					(thickness 0.15)
				)
				(justify left bottom)
				(hide yes)
			)
		)
		(property "Footprint" "antmicro-footprints:C_0402_1005Metric"
			(at 245.11 82.55 0)
			(effects
				(font
					(size 1.27 1.27)
					(thickness 0.15)
				)
				(justify left bottom)
				(hide yes)
			)
		)
		(property "Datasheet" "https://www.murata.com/products/productdetail?partno=GRM155R61H104KE14%23"
			(at 247.65 82.55 0)
			(effects
				(font
					(size 1.27 1.27)
					(thickness 0.15)
				)
				(justify left bottom)
				(hide yes)
			)
		)
		(property "Description" "SMD Multilayer Ceramic Capacitor, 0.1 µF, 50 V, 0402 [1005 Metric], ± 10%, X5R, GRM Series"
			(at 232.41 102.87 0)
			(effects
				(font
					(size 1.27 1.27)
				)
				(hide yes)
			)
		)
		(property "MPN" "GRM155R61H104KE14D"
			(at 250.19 82.55 0)
			(effects
				(font
					(size 1.27 1.27)
					(thickness 0.15)
				)
				(justify left bottom)
				(hide yes)
			)
		)
		(property "Manufacturer" "Murata"
			(at 252.73 82.55 0)
			(effects
				(font
					(size 1.27 1.27)
					(thickness 0.15)
				)
				(justify left bottom)
				(hide yes)
			)
		)
		(property "License" "Apache-2.0"
			(at 255.27 82.55 0)
			(effects
				(font
					(size 1.27 1.27)
					(thickness 0.15)
				)
				(justify left bottom)
				(hide yes)
			)
		)
		(property "Author" "Antmicro"
			(at 257.81 82.55 0)
			(effects
				(font
					(size 1.27 1.27)
					(thickness 0.15)
				)
				(justify left bottom)
				(hide yes)
			)
		)
		(property "Val" "100n"
			(at 233.045 102.235 90)
			(effects
				(font
					(size 1.27 1.27)
					(thickness 0.15)
				)
				(justify right)
			)
		)
		(property "Voltage" "50V"
			(at 260.35 82.55 0)
			(effects
				(font
					(size 1.27 1.27)
				)
				(justify left bottom)
				(hide yes)
			)
		)
		(property "Dielectric" "X5R"
			(at 262.89 82.55 0)
			(effects
				(font
					(size 1.27 1.27)
				)
				(justify left bottom)
				(hide yes)
			)
		)
		(pin "1"
		)
		(pin "2"
		)
		(instances
			(project "gmsl-deserializer"
				(path ""
					(reference "C39")
					(unit 1)
				)
			)
		)
	)
	(symbol
		(lib_id "antmicropower:GND")
		(at 252.73 201.93 0)
		(unit 1)
		(exclude_from_sim no)
		(in_bom yes)
		(on_board yes)
		(dnp no)
		(property "Reference" "#PWR087"
			(at 261.62 204.47 0)
			(effects
				(font
					(size 1.27 1.27)
					(thickness 0.15)
				)
				(justify left bottom)
				(hide yes)
			)
		)
		(property "Value" "GND"
			(at 252.73 205.74 0)
			(effects
				(font
					(size 1.27 1.27)
					(thickness 0.15)
				)
			)
		)
		(property "Footprint" ""
			(at 261.62 209.55 0)
			(effects
				(font
					(size 1.27 1.27)
					(thickness 0.15)
				)
				(justify left bottom)
				(hide yes)
			)
		)
		(property "Datasheet" ""
			(at 261.62 214.63 0)
			(effects
				(font
					(size 1.27 1.27)
					(thickness 0.15)
				)
				(justify left bottom)
				(hide yes)
			)
		)
		(property "Description" ""
			(at 252.73 201.93 0)
			(effects
				(font
					(size 1.27 1.27)
				)
				(hide yes)
			)
		)
		(property "Author" "Antmicro"
			(at 261.62 209.55 0)
			(effects
				(font
					(size 1.27 1.27)
					(thickness 0.15)
				)
				(justify left bottom)
				(hide yes)
			)
		)
		(property "License" "Apache-2.0"
			(at 261.62 212.09 0)
			(effects
				(font
					(size 1.27 1.27)
					(thickness 0.15)
				)
				(justify left bottom)
				(hide yes)
			)
		)
		(pin "1"
		)
		(instances
			(project "gmsl-deserializer"
				(path ""
					(reference "#PWR087")
					(unit 1)
				)
			)
		)
	)
	(symbol
		(lib_id "antmicroResistors0402:R_0R_0402")
		(at 214.63 114.3 90)
		(unit 1)
		(exclude_from_sim no)
		(in_bom yes)
		(on_board yes)
		(dnp no)
		(property "Reference" "R53"
			(at 216.535 110.4899 90)
			(effects
				(font
					(size 1.27 1.27)
					(thickness 0.15)
				)
				(justify right)
			)
		)
		(property "Value" "R_0R_0402"
			(at 227.33 93.98 0)
			(effects
				(font
					(size 1.27 1.27)
					(thickness 0.15)
				)
				(justify left bottom)
				(hide yes)
			)
		)
		(property "Footprint" "antmicro-footprints:R_0402_1005Metric"
			(at 229.87 93.98 0)
			(effects
				(font
					(size 1.27 1.27)
					(thickness 0.15)
				)
				(justify left bottom)
				(hide yes)
			)
		)
		(property "Datasheet" "https://industrial.panasonic.com/cdbs/www-data/pdf/RDA0000/AOA0000C301.pdf"
			(at 232.41 93.98 0)
			(effects
				(font
					(size 1.27 1.27)
					(thickness 0.15)
				)
				(justify left bottom)
				(hide yes)
			)
		)
		(property "Description" "SMD Chip Resistor, Jumper, 0 ohm, 100 mW, 0402 [1005 Metric], Thick Film, General Purpose"
			(at 214.63 114.3 0)
			(effects
				(font
					(size 1.27 1.27)
				)
				(hide yes)
			)
		)
		(property "MPN" "ERJ2GE0R00X"
			(at 234.95 93.98 0)
			(effects
				(font
					(size 1.27 1.27)
					(thickness 0.15)
				)
				(justify left bottom)
				(hide yes)
			)
		)
		(property "Manufacturer" "Panasonic"
			(at 237.49 93.98 0)
			(effects
				(font
					(size 1.27 1.27)
					(thickness 0.15)
				)
				(justify left bottom)
				(hide yes)
			)
		)
		(property "License" "Apache-2.0"
			(at 240.03 93.98 0)
			(effects
				(font
					(size 1.27 1.27)
					(thickness 0.15)
				)
				(justify left bottom)
				(hide yes)
			)
		)
		(property "Author" "Antmicro"
			(at 242.57 93.98 0)
			(effects
				(font
					(size 1.27 1.27)
					(thickness 0.15)
				)
				(justify left bottom)
				(hide yes)
			)
		)
		(property "Val" "0R"
			(at 216.535 113.0299 90)
			(effects
				(font
					(size 1.27 1.27)
					(thickness 0.15)
				)
				(justify right)
			)
		)
		(property "Tolerance" "~"
			(at 224.79 93.98 0)
			(effects
				(font
					(size 1.27 1.27)
				)
				(justify left bottom)
				(hide yes)
			)
		)
		(property "Current" "1A"
			(at 245.11 93.98 0)
			(effects
				(font
					(size 1.27 1.27)
					(thickness 0.15)
				)
				(justify left bottom)
				(hide yes)
			)
		)
		(pin "1"
		)
		(pin "2"
		)
		(instances
			(project "gmsl-deserializer"
				(path ""
					(reference "R53")
					(unit 1)
				)
			)
		)
	)
	(symbol
		(lib_id "antmicropower:GND")
		(at 232.41 123.19 0)
		(unit 1)
		(exclude_from_sim no)
		(in_bom yes)
		(on_board yes)
		(dnp no)
		(property "Reference" "#PWR080"
			(at 241.3 125.73 0)
			(effects
				(font
					(size 1.27 1.27)
					(thickness 0.15)
				)
				(justify left bottom)
				(hide yes)
			)
		)
		(property "Value" "GND"
			(at 232.41 127 0)
			(effects
				(font
					(size 1.27 1.27)
					(thickness 0.15)
				)
			)
		)
		(property "Footprint" ""
			(at 241.3 130.81 0)
			(effects
				(font
					(size 1.27 1.27)
					(thickness 0.15)
				)
				(justify left bottom)
				(hide yes)
			)
		)
		(property "Datasheet" ""
			(at 241.3 135.89 0)
			(effects
				(font
					(size 1.27 1.27)
					(thickness 0.15)
				)
				(justify left bottom)
				(hide yes)
			)
		)
		(property "Description" ""
			(at 232.41 123.19 0)
			(effects
				(font
					(size 1.27 1.27)
				)
				(hide yes)
			)
		)
		(property "Author" "Antmicro"
			(at 241.3 130.81 0)
			(effects
				(font
					(size 1.27 1.27)
					(thickness 0.15)
				)
				(justify left bottom)
				(hide yes)
			)
		)
		(property "License" "Apache-2.0"
			(at 241.3 133.35 0)
			(effects
				(font
					(size 1.27 1.27)
					(thickness 0.15)
				)
				(justify left bottom)
				(hide yes)
			)
		)
		(pin "1"
		)
		(instances
			(project "gmsl-deserializer"
				(path ""
					(reference "#PWR080")
					(unit 1)
				)
			)
		)
	)
	(symbol
		(lib_id "antmicropower:GND")
		(at 242.57 123.19 0)
		(unit 1)
		(exclude_from_sim no)
		(in_bom yes)
		(on_board yes)
		(dnp no)
		(property "Reference" "#PWR083"
			(at 251.46 125.73 0)
			(effects
				(font
					(size 1.27 1.27)
					(thickness 0.15)
				)
				(justify left bottom)
				(hide yes)
			)
		)
		(property "Value" "GND"
			(at 242.57 127 0)
			(effects
				(font
					(size 1.27 1.27)
					(thickness 0.15)
				)
			)
		)
		(property "Footprint" ""
			(at 251.46 130.81 0)
			(effects
				(font
					(size 1.27 1.27)
					(thickness 0.15)
				)
				(justify left bottom)
				(hide yes)
			)
		)
		(property "Datasheet" ""
			(at 251.46 135.89 0)
			(effects
				(font
					(size 1.27 1.27)
					(thickness 0.15)
				)
				(justify left bottom)
				(hide yes)
			)
		)
		(property "Description" ""
			(at 242.57 123.19 0)
			(effects
				(font
					(size 1.27 1.27)
				)
				(hide yes)
			)
		)
		(property "Author" "Antmicro"
			(at 251.46 130.81 0)
			(effects
				(font
					(size 1.27 1.27)
					(thickness 0.15)
				)
				(justify left bottom)
				(hide yes)
			)
		)
		(property "License" "Apache-2.0"
			(at 251.46 133.35 0)
			(effects
				(font
					(size 1.27 1.27)
					(thickness 0.15)
				)
				(justify left bottom)
				(hide yes)
			)
		)
		(pin "1"
		)
		(instances
			(project "gmsl-deserializer"
				(path ""
					(reference "#PWR083")
					(unit 1)
				)
			)
		)
	)
	(symbol
		(lib_id "antmicroCapacitors0402:C_10n_0402")
		(at 242.57 102.87 90)
		(unit 1)
		(exclude_from_sim no)
		(in_bom yes)
		(on_board yes)
		(dnp no)
		(property "Reference" "C42"
			(at 243.205 98.425 90)
			(effects
				(font
					(size 1.27 1.27)
					(thickness 0.15)
				)
				(justify right)
			)
		)
		(property "Value" "C_10n_0402"
			(at 252.73 82.55 0)
			(effects
				(font
					(size 1.27 1.27)
					(thickness 0.15)
				)
				(justify left bottom)
				(hide yes)
			)
		)
		(property "Footprint" "antmicro-footprints:C_0402_1005Metric"
			(at 255.27 82.55 0)
			(effects
				(font
					(size 1.27 1.27)
					(thickness 0.15)
				)
				(justify left bottom)
				(hide yes)
			)
		)
		(property "Datasheet" "https://www.murata.com/products/productdetail?partno=GRM155R71H103KA88%23"
			(at 257.81 82.55 0)
			(effects
				(font
					(size 1.27 1.27)
					(thickness 0.15)
				)
				(justify left bottom)
				(hide yes)
			)
		)
		(property "Description" "SMD Multilayer Ceramic Capacitor, 10000 pF, 50 V, 0402 [1005 Metric], ± 10%, X7R, GRM Series"
			(at 242.57 102.87 0)
			(effects
				(font
					(size 1.27 1.27)
				)
				(hide yes)
			)
		)
		(property "MPN" "GRM155R71H103KA88D"
			(at 260.35 82.55 0)
			(effects
				(font
					(size 1.27 1.27)
					(thickness 0.15)
				)
				(justify left bottom)
				(hide yes)
			)
		)
		(property "Manufacturer" "Murata"
			(at 262.89 82.55 0)
			(effects
				(font
					(size 1.27 1.27)
					(thickness 0.15)
				)
				(justify left bottom)
				(hide yes)
			)
		)
		(property "License" "Apache-2.0"
			(at 265.43 82.55 0)
			(effects
				(font
					(size 1.27 1.27)
					(thickness 0.15)
				)
				(justify left bottom)
				(hide yes)
			)
		)
		(property "Author" "Antmicro"
			(at 267.97 82.55 0)
			(effects
				(font
					(size 1.27 1.27)
					(thickness 0.15)
				)
				(justify left bottom)
				(hide yes)
			)
		)
		(property "Val" "10n"
			(at 243.205 102.235 90)
			(effects
				(font
					(size 1.27 1.27)
					(thickness 0.15)
				)
				(justify right)
			)
		)
		(property "Voltage" "50V"
			(at 270.51 82.55 0)
			(effects
				(font
					(size 1.27 1.27)
				)
				(justify left bottom)
				(hide yes)
			)
		)
		(property "Dielectric" "X7R"
			(at 273.05 82.55 0)
			(effects
				(font
					(size 1.27 1.27)
				)
				(justify left bottom)
				(hide yes)
			)
		)
		(pin "1"
		)
		(pin "2"
		)
		(instances
			(project "gmsl-deserializer"
				(path ""
					(reference "C42")
					(unit 1)
				)
			)
		)
	)
	(symbol
		(lib_id "antmicropower:GND")
		(at 360.68 104.14 0)
		(mirror y)
		(unit 1)
		(exclude_from_sim no)
		(in_bom yes)
		(on_board yes)
		(dnp no)
		(property "Reference" "#PWR096"
			(at 351.79 106.68 0)
			(effects
				(font
					(size 1.27 1.27)
					(thickness 0.15)
				)
				(justify left bottom)
				(hide yes)
			)
		)
		(property "Value" "GND"
			(at 360.68 107.95 0)
			(effects
				(font
					(size 1.27 1.27)
					(thickness 0.15)
				)
			)
		)
		(property "Footprint" ""
			(at 351.79 111.76 0)
			(effects
				(font
					(size 1.27 1.27)
					(thickness 0.15)
				)
				(justify left bottom)
				(hide yes)
			)
		)
		(property "Datasheet" ""
			(at 351.79 116.84 0)
			(effects
				(font
					(size 1.27 1.27)
					(thickness 0.15)
				)
				(justify left bottom)
				(hide yes)
			)
		)
		(property "Description" ""
			(at 360.68 104.14 0)
			(effects
				(font
					(size 1.27 1.27)
				)
				(hide yes)
			)
		)
		(property "Author" "Antmicro"
			(at 351.79 111.76 0)
			(effects
				(font
					(size 1.27 1.27)
					(thickness 0.15)
				)
				(justify left bottom)
				(hide yes)
			)
		)
		(property "License" "Apache-2.0"
			(at 351.79 114.3 0)
			(effects
				(font
					(size 1.27 1.27)
					(thickness 0.15)
				)
				(justify left bottom)
				(hide yes)
			)
		)
		(pin "1"
		)
		(instances
			(project "gmsl-deserializer"
				(path ""
					(reference "#PWR096")
					(unit 1)
				)
			)
		)
	)
	(symbol
		(lib_id "antmicropower:GND")
		(at 243.84 201.93 0)
		(unit 1)
		(exclude_from_sim no)
		(in_bom yes)
		(on_board yes)
		(dnp no)
		(property "Reference" "#PWR084"
			(at 252.73 204.47 0)
			(effects
				(font
					(size 1.27 1.27)
					(thickness 0.15)
				)
				(justify left bottom)
				(hide yes)
			)
		)
		(property "Value" "GND"
			(at 243.84 205.74 0)
			(effects
				(font
					(size 1.27 1.27)
					(thickness 0.15)
				)
			)
		)
		(property "Footprint" ""
			(at 252.73 209.55 0)
			(effects
				(font
					(size 1.27 1.27)
					(thickness 0.15)
				)
				(justify left bottom)
				(hide yes)
			)
		)
		(property "Datasheet" ""
			(at 252.73 214.63 0)
			(effects
				(font
					(size 1.27 1.27)
					(thickness 0.15)
				)
				(justify left bottom)
				(hide yes)
			)
		)
		(property "Description" ""
			(at 243.84 201.93 0)
			(effects
				(font
					(size 1.27 1.27)
				)
				(hide yes)
			)
		)
		(property "Author" "Antmicro"
			(at 252.73 209.55 0)
			(effects
				(font
					(size 1.27 1.27)
					(thickness 0.15)
				)
				(justify left bottom)
				(hide yes)
			)
		)
		(property "License" "Apache-2.0"
			(at 252.73 212.09 0)
			(effects
				(font
					(size 1.27 1.27)
					(thickness 0.15)
				)
				(justify left bottom)
				(hide yes)
			)
		)
		(pin "1"
		)
		(instances
			(project "gmsl-deserializer"
				(path ""
					(reference "#PWR084")
					(unit 1)
				)
			)
		)
	)
	(symbol
		(lib_id "antmicroCapacitors0402:C_100n_0402")
		(at 86.36 119.38 180)
		(unit 1)
		(exclude_from_sim no)
		(in_bom yes)
		(on_board yes)
		(dnp no)
		(property "Reference" "C30"
			(at 82.55 118.11 0)
			(effects
				(font
					(size 1.27 1.27)
					(thickness 0.15)
				)
				(justify left)
			)
		)
		(property "Value" "C_100n_0402"
			(at 66.04 109.22 0)
			(effects
				(font
					(size 1.27 1.27)
					(thickness 0.15)
				)
				(justify left bottom)
				(hide yes)
			)
		)
		(property "Footprint" "antmicro-footprints:C_0402_1005Metric"
			(at 66.04 106.68 0)
			(effects
				(font
					(size 1.27 1.27)
					(thickness 0.15)
				)
				(justify left bottom)
				(hide yes)
			)
		)
		(property "Datasheet" "https://www.murata.com/products/productdetail?partno=GRM155R61H104KE14%23"
			(at 66.04 104.14 0)
			(effects
				(font
					(size 1.27 1.27)
					(thickness 0.15)
				)
				(justify left bottom)
				(hide yes)
			)
		)
		(property "Description" "SMD Multilayer Ceramic Capacitor, 0.1 µF, 50 V, 0402 [1005 Metric], ± 10%, X5R, GRM Series"
			(at 86.36 119.38 0)
			(effects
				(font
					(size 1.27 1.27)
				)
				(hide yes)
			)
		)
		(property "MPN" "GRM155R61H104KE14D"
			(at 66.04 101.6 0)
			(effects
				(font
					(size 1.27 1.27)
					(thickness 0.15)
				)
				(justify left bottom)
				(hide yes)
			)
		)
		(property "Manufacturer" "Murata"
			(at 66.04 99.06 0)
			(effects
				(font
					(size 1.27 1.27)
					(thickness 0.15)
				)
				(justify left bottom)
				(hide yes)
			)
		)
		(property "License" "Apache-2.0"
			(at 66.04 96.52 0)
			(effects
				(font
					(size 1.27 1.27)
					(thickness 0.15)
				)
				(justify left bottom)
				(hide yes)
			)
		)
		(property "Author" "Antmicro"
			(at 66.04 93.98 0)
			(effects
				(font
					(size 1.27 1.27)
					(thickness 0.15)
				)
				(justify left bottom)
				(hide yes)
			)
		)
		(property "Val" "100n"
			(at 85.09 118.11 0)
			(effects
				(font
					(size 1.27 1.27)
					(thickness 0.15)
				)
				(justify right)
			)
		)
		(property "Voltage" "50V"
			(at 66.04 91.44 0)
			(effects
				(font
					(size 1.27 1.27)
				)
				(justify left bottom)
				(hide yes)
			)
		)
		(property "Dielectric" "X5R"
			(at 66.04 88.9 0)
			(effects
				(font
					(size 1.27 1.27)
				)
				(justify left bottom)
				(hide yes)
			)
		)
		(pin "1"
		)
		(pin "2"
		)
		(instances
			(project "gmsl-deserializer"
				(path ""
					(reference "C30")
					(unit 1)
				)
			)
		)
	)
	(symbol
		(lib_id "antmicropower:GND")
		(at 232.41 104.14 0)
		(unit 1)
		(exclude_from_sim no)
		(in_bom yes)
		(on_board yes)
		(dnp no)
		(property "Reference" "#PWR079"
			(at 241.3 106.68 0)
			(effects
				(font
					(size 1.27 1.27)
					(thickness 0.15)
				)
				(justify left bottom)
				(hide yes)
			)
		)
		(property "Value" "GND"
			(at 232.41 107.95 0)
			(effects
				(font
					(size 1.27 1.27)
					(thickness 0.15)
				)
			)
		)
		(property "Footprint" ""
			(at 241.3 111.76 0)
			(effects
				(font
					(size 1.27 1.27)
					(thickness 0.15)
				)
				(justify left bottom)
				(hide yes)
			)
		)
		(property "Datasheet" ""
			(at 241.3 116.84 0)
			(effects
				(font
					(size 1.27 1.27)
					(thickness 0.15)
				)
				(justify left bottom)
				(hide yes)
			)
		)
		(property "Description" ""
			(at 232.41 104.14 0)
			(effects
				(font
					(size 1.27 1.27)
				)
				(hide yes)
			)
		)
		(property "Author" "Antmicro"
			(at 241.3 111.76 0)
			(effects
				(font
					(size 1.27 1.27)
					(thickness 0.15)
				)
				(justify left bottom)
				(hide yes)
			)
		)
		(property "License" "Apache-2.0"
			(at 241.3 114.3 0)
			(effects
				(font
					(size 1.27 1.27)
					(thickness 0.15)
				)
				(justify left bottom)
				(hide yes)
			)
		)
		(pin "1"
		)
		(instances
			(project "gmsl-deserializer"
				(path ""
					(reference "#PWR079")
					(unit 1)
				)
			)
		)
	)
	(symbol
		(lib_id "antmicroCapacitors0402:C_10u_0402")
		(at 361.95 124.46 90)
		(unit 1)
		(exclude_from_sim no)
		(in_bom yes)
		(on_board yes)
		(dnp no)
		(property "Reference" "C55"
			(at 362.585 120.015 90)
			(effects
				(font
					(size 1.27 1.27)
					(thickness 0.15)
				)
				(justify right)
			)
		)
		(property "Value" "C_10u_0402"
			(at 372.11 104.14 0)
			(effects
				(font
					(size 1.27 1.27)
					(thickness 0.15)
				)
				(justify left bottom)
				(hide yes)
			)
		)
		(property "Footprint" "antmicro-footprints:C_0402_1005Metric"
			(at 374.65 104.14 0)
			(effects
				(font
					(size 1.27 1.27)
					(thickness 0.15)
				)
				(justify left bottom)
				(hide yes)
			)
		)
		(property "Datasheet" "https://www.yageo.com/en/Chart/Download/pdf/CC0402MRX5R5BB106"
			(at 377.19 104.14 0)
			(effects
				(font
					(size 1.27 1.27)
					(thickness 0.15)
				)
				(justify left bottom)
				(hide yes)
			)
		)
		(property "Description" "SMD Multilayer Ceramic Capacitor, 10 µF, 6.3 V, 0402 [1005 Metric], ± 20%, X5R, CC Series"
			(at 361.95 124.46 0)
			(effects
				(font
					(size 1.27 1.27)
				)
				(hide yes)
			)
		)
		(property "MPN" "CC0402MRX5R5BB106"
			(at 379.73 104.14 0)
			(effects
				(font
					(size 1.27 1.27)
					(thickness 0.15)
				)
				(justify left bottom)
				(hide yes)
			)
		)
		(property "Manufacturer" "YAGEO"
			(at 382.27 104.14 0)
			(effects
				(font
					(size 1.27 1.27)
					(thickness 0.15)
				)
				(justify left bottom)
				(hide yes)
			)
		)
		(property "License" "Apache-2.0"
			(at 384.81 104.14 0)
			(effects
				(font
					(size 1.27 1.27)
					(thickness 0.15)
				)
				(justify left bottom)
				(hide yes)
			)
		)
		(property "Author" "Antmicro"
			(at 387.35 104.14 0)
			(effects
				(font
					(size 1.27 1.27)
					(thickness 0.15)
				)
				(justify left bottom)
				(hide yes)
			)
		)
		(property "Val" "10u"
			(at 362.585 123.825 90)
			(effects
				(font
					(size 1.27 1.27)
					(thickness 0.15)
				)
				(justify right)
			)
		)
		(property "Voltage" ""
			(at 389.89 104.14 0)
			(effects
				(font
					(size 1.27 1.27)
				)
				(justify left bottom)
				(hide yes)
			)
		)
		(property "Dielectric" ""
			(at 392.43 104.14 0)
			(effects
				(font
					(size 1.27 1.27)
				)
				(justify left bottom)
				(hide yes)
			)
		)
		(pin "1"
		)
		(pin "2"
		)
		(instances
			(project "gmsl-deserializer"
				(path ""
					(reference "C55")
					(unit 1)
				)
			)
		)
	)
	(symbol
		(lib_id "antmicroResistors0402:R_49R9_0402")
		(at 74.93 121.92 0)
		(mirror y)
		(unit 1)
		(exclude_from_sim no)
		(in_bom yes)
		(on_board yes)
		(dnp no)
		(property "Reference" "R46"
			(at 69.215 123.825 0)
			(effects
				(font
					(size 1.27 1.27)
					(thickness 0.15)
				)
			)
		)
		(property "Value" "R_49R9_0402"
			(at 54.61 134.62 0)
			(effects
				(font
					(size 1.27 1.27)
					(thickness 0.15)
				)
				(justify left bottom)
				(hide yes)
			)
		)
		(property "Footprint" "antmicro-footprints:R_0402_1005Metric"
			(at 54.61 137.16 0)
			(effects
				(font
					(size 1.27 1.27)
					(thickness 0.15)
				)
				(justify left bottom)
				(hide yes)
			)
		)
		(property "Datasheet" "https://www.bourns.com/docs/product-datasheets/cr.pdf"
			(at 54.61 139.7 0)
			(effects
				(font
					(size 1.27 1.27)
					(thickness 0.15)
				)
				(justify left bottom)
				(hide yes)
			)
		)
		(property "Description" "SMD Chip Resistor, 49.9 ohm, ± 1%, 62.5 mW, 0402 [1005 Metric], Thick Film, General Purpose"
			(at 74.93 121.92 0)
			(effects
				(font
					(size 1.27 1.27)
				)
				(hide yes)
			)
		)
		(property "MPN" "CR0402-FX-49R9GLF"
			(at 54.61 142.24 0)
			(effects
				(font
					(size 1.27 1.27)
					(thickness 0.15)
				)
				(justify left bottom)
				(hide yes)
			)
		)
		(property "Manufacturer" "Bourns"
			(at 54.61 144.78 0)
			(effects
				(font
					(size 1.27 1.27)
					(thickness 0.15)
				)
				(justify left bottom)
				(hide yes)
			)
		)
		(property "License" "Apache-2.0"
			(at 54.61 147.32 0)
			(effects
				(font
					(size 1.27 1.27)
					(thickness 0.15)
				)
				(justify left bottom)
				(hide yes)
			)
		)
		(property "Author" "Antmicro"
			(at 54.61 149.86 0)
			(effects
				(font
					(size 1.27 1.27)
					(thickness 0.15)
				)
				(justify left bottom)
				(hide yes)
			)
		)
		(property "Val" "49R9"
			(at 74.295 123.825 0)
			(effects
				(font
					(size 1.27 1.27)
					(thickness 0.15)
				)
			)
		)
		(property "Tolerance" "1%"
			(at 54.61 132.08 0)
			(effects
				(font
					(size 1.27 1.27)
				)
				(justify left bottom)
				(hide yes)
			)
		)
		(pin "1"
		)
		(pin "2"
		)
		(instances
			(project "gmsl-deserializer"
				(path ""
					(reference "R46")
					(unit 1)
				)
			)
		)
	)
	(symbol
		(lib_id "antmicropower:GND")
		(at 261.62 104.14 0)
		(unit 1)
		(exclude_from_sim no)
		(in_bom yes)
		(on_board yes)
		(dnp no)
		(property "Reference" "#PWR088"
			(at 270.51 106.68 0)
			(effects
				(font
					(size 1.27 1.27)
					(thickness 0.15)
				)
				(justify left bottom)
				(hide yes)
			)
		)
		(property "Value" "GND"
			(at 261.62 107.95 0)
			(effects
				(font
					(size 1.27 1.27)
					(thickness 0.15)
				)
			)
		)
		(property "Footprint" ""
			(at 270.51 111.76 0)
			(effects
				(font
					(size 1.27 1.27)
					(thickness 0.15)
				)
				(justify left bottom)
				(hide yes)
			)
		)
		(property "Datasheet" ""
			(at 270.51 116.84 0)
			(effects
				(font
					(size 1.27 1.27)
					(thickness 0.15)
				)
				(justify left bottom)
				(hide yes)
			)
		)
		(property "Description" ""
			(at 261.62 104.14 0)
			(effects
				(font
					(size 1.27 1.27)
				)
				(hide yes)
			)
		)
		(property "Author" "Antmicro"
			(at 270.51 111.76 0)
			(effects
				(font
					(size 1.27 1.27)
					(thickness 0.15)
				)
				(justify left bottom)
				(hide yes)
			)
		)
		(property "License" "Apache-2.0"
			(at 270.51 114.3 0)
			(effects
				(font
					(size 1.27 1.27)
					(thickness 0.15)
				)
				(justify left bottom)
				(hide yes)
			)
		)
		(pin "1"
		)
		(instances
			(project "gmsl-deserializer"
				(path ""
					(reference "#PWR088")
					(unit 1)
				)
			)
		)
	)
	(symbol
		(lib_id "antmicroCapacitors0402:C_100n_0402")
		(at 86.36 111.76 180)
		(unit 1)
		(exclude_from_sim no)
		(in_bom yes)
		(on_board yes)
		(dnp no)
		(property "Reference" "C29"
			(at 82.55 110.49 0)
			(effects
				(font
					(size 1.27 1.27)
					(thickness 0.15)
				)
				(justify left)
			)
		)
		(property "Value" "C_100n_0402"
			(at 66.04 101.6 0)
			(effects
				(font
					(size 1.27 1.27)
					(thickness 0.15)
				)
				(justify left bottom)
				(hide yes)
			)
		)
		(property "Footprint" "antmicro-footprints:C_0402_1005Metric"
			(at 66.04 99.06 0)
			(effects
				(font
					(size 1.27 1.27)
					(thickness 0.15)
				)
				(justify left bottom)
				(hide yes)
			)
		)
		(property "Datasheet" "https://www.murata.com/products/productdetail?partno=GRM155R61H104KE14%23"
			(at 66.04 96.52 0)
			(effects
				(font
					(size 1.27 1.27)
					(thickness 0.15)
				)
				(justify left bottom)
				(hide yes)
			)
		)
		(property "Description" "SMD Multilayer Ceramic Capacitor, 0.1 µF, 50 V, 0402 [1005 Metric], ± 10%, X5R, GRM Series"
			(at 86.36 111.76 0)
			(effects
				(font
					(size 1.27 1.27)
				)
				(hide yes)
			)
		)
		(property "MPN" "GRM155R61H104KE14D"
			(at 66.04 93.98 0)
			(effects
				(font
					(size 1.27 1.27)
					(thickness 0.15)
				)
				(justify left bottom)
				(hide yes)
			)
		)
		(property "Manufacturer" "Murata"
			(at 66.04 91.44 0)
			(effects
				(font
					(size 1.27 1.27)
					(thickness 0.15)
				)
				(justify left bottom)
				(hide yes)
			)
		)
		(property "License" "Apache-2.0"
			(at 66.04 88.9 0)
			(effects
				(font
					(size 1.27 1.27)
					(thickness 0.15)
				)
				(justify left bottom)
				(hide yes)
			)
		)
		(property "Author" "Antmicro"
			(at 66.04 86.36 0)
			(effects
				(font
					(size 1.27 1.27)
					(thickness 0.15)
				)
				(justify left bottom)
				(hide yes)
			)
		)
		(property "Val" "100n"
			(at 85.09 110.49 0)
			(effects
				(font
					(size 1.27 1.27)
					(thickness 0.15)
				)
				(justify right)
			)
		)
		(property "Voltage" "50V"
			(at 66.04 83.82 0)
			(effects
				(font
					(size 1.27 1.27)
				)
				(justify left bottom)
				(hide yes)
			)
		)
		(property "Dielectric" "X5R"
			(at 66.04 81.28 0)
			(effects
				(font
					(size 1.27 1.27)
				)
				(justify left bottom)
				(hide yes)
			)
		)
		(pin "1"
		)
		(pin "2"
		)
		(instances
			(project "gmsl-deserializer"
				(path ""
					(reference "C29")
					(unit 1)
				)
			)
		)
	)
	(symbol
		(lib_id "antmicropower:GND")
		(at 223.52 123.19 0)
		(unit 1)
		(exclude_from_sim no)
		(in_bom yes)
		(on_board yes)
		(dnp no)
		(property "Reference" "#PWR077"
			(at 232.41 125.73 0)
			(effects
				(font
					(size 1.27 1.27)
					(thickness 0.15)
				)
				(justify left bottom)
				(hide yes)
			)
		)
		(property "Value" "GND"
			(at 223.52 127 0)
			(effects
				(font
					(size 1.27 1.27)
					(thickness 0.15)
				)
			)
		)
		(property "Footprint" ""
			(at 232.41 130.81 0)
			(effects
				(font
					(size 1.27 1.27)
					(thickness 0.15)
				)
				(justify left bottom)
				(hide yes)
			)
		)
		(property "Datasheet" ""
			(at 232.41 135.89 0)
			(effects
				(font
					(size 1.27 1.27)
					(thickness 0.15)
				)
				(justify left bottom)
				(hide yes)
			)
		)
		(property "Description" ""
			(at 223.52 123.19 0)
			(effects
				(font
					(size 1.27 1.27)
				)
				(hide yes)
			)
		)
		(property "Author" "Antmicro"
			(at 232.41 130.81 0)
			(effects
				(font
					(size 1.27 1.27)
					(thickness 0.15)
				)
				(justify left bottom)
				(hide yes)
			)
		)
		(property "License" "Apache-2.0"
			(at 232.41 133.35 0)
			(effects
				(font
					(size 1.27 1.27)
					(thickness 0.15)
				)
				(justify left bottom)
				(hide yes)
			)
		)
		(pin "1"
		)
		(instances
			(project "gmsl-deserializer"
				(path ""
					(reference "#PWR077")
					(unit 1)
				)
			)
		)
	)
	(symbol
		(lib_id "antmicroResistors0402:R_0R_0402")
		(at 214.63 95.25 90)
		(unit 1)
		(exclude_from_sim no)
		(in_bom yes)
		(on_board yes)
		(dnp no)
		(property "Reference" "R52"
			(at 216.535 91.44 90)
			(effects
				(font
					(size 1.27 1.27)
					(thickness 0.15)
				)
				(justify right)
			)
		)
		(property "Value" "R_0R_0402"
			(at 227.33 74.93 0)
			(effects
				(font
					(size 1.27 1.27)
					(thickness 0.15)
				)
				(justify left bottom)
				(hide yes)
			)
		)
		(property "Footprint" "antmicro-footprints:R_0402_1005Metric"
			(at 229.87 74.93 0)
			(effects
				(font
					(size 1.27 1.27)
					(thickness 0.15)
				)
				(justify left bottom)
				(hide yes)
			)
		)
		(property "Datasheet" "https://industrial.panasonic.com/cdbs/www-data/pdf/RDA0000/AOA0000C301.pdf"
			(at 232.41 74.93 0)
			(effects
				(font
					(size 1.27 1.27)
					(thickness 0.15)
				)
				(justify left bottom)
				(hide yes)
			)
		)
		(property "Description" "SMD Chip Resistor, Jumper, 0 ohm, 100 mW, 0402 [1005 Metric], Thick Film, General Purpose"
			(at 214.63 95.25 0)
			(effects
				(font
					(size 1.27 1.27)
				)
				(hide yes)
			)
		)
		(property "MPN" "ERJ2GE0R00X"
			(at 234.95 74.93 0)
			(effects
				(font
					(size 1.27 1.27)
					(thickness 0.15)
				)
				(justify left bottom)
				(hide yes)
			)
		)
		(property "Manufacturer" "Panasonic"
			(at 237.49 74.93 0)
			(effects
				(font
					(size 1.27 1.27)
					(thickness 0.15)
				)
				(justify left bottom)
				(hide yes)
			)
		)
		(property "License" "Apache-2.0"
			(at 240.03 74.93 0)
			(effects
				(font
					(size 1.27 1.27)
					(thickness 0.15)
				)
				(justify left bottom)
				(hide yes)
			)
		)
		(property "Author" "Antmicro"
			(at 242.57 74.93 0)
			(effects
				(font
					(size 1.27 1.27)
					(thickness 0.15)
				)
				(justify left bottom)
				(hide yes)
			)
		)
		(property "Val" "0R"
			(at 216.535 93.98 90)
			(effects
				(font
					(size 1.27 1.27)
					(thickness 0.15)
				)
				(justify right)
			)
		)
		(property "Tolerance" "~"
			(at 224.79 74.93 0)
			(effects
				(font
					(size 1.27 1.27)
				)
				(justify left bottom)
				(hide yes)
			)
		)
		(property "Current" "1A"
			(at 245.11 74.93 0)
			(effects
				(font
					(size 1.27 1.27)
					(thickness 0.15)
				)
				(justify left bottom)
				(hide yes)
			)
		)
		(pin "1"
		)
		(pin "2"
		)
		(instances
			(project "gmsl-deserializer"
				(path ""
					(reference "R52")
					(unit 1)
				)
			)
		)
	)
	(symbol
		(lib_id "antmicroTVSDiodes:PESD4USB5U-TTS")
		(at 127 127 270)
		(unit 1)
		(exclude_from_sim no)
		(in_bom yes)
		(on_board yes)
		(dnp no)
		(property "Reference" "D5"
			(at 115.57 135.89 90)
			(effects
				(font
					(size 1.27 1.27)
					(thickness 0.15)
				)
				(justify left)
			)
		)
		(property "Value" "PESD4USB5U-TTS"
			(at 115.57 137.795 90)
			(effects
				(font
					(size 1.27 1.27)
					(thickness 0.15)
				)
				(justify left)
			)
		)
		(property "Footprint" "antmicro-footprints:DFN-10_2.5x1mm"
			(at 113.03 126.365 0)
			(effects
				(font
					(size 1.27 1.27)
					(thickness 0.15)
				)
				(justify left bottom)
				(hide yes)
			)
		)
		(property "Datasheet" "https://assets.nexperia.com/documents/data-sheet/PESD4USB5U-TTS.pdf"
			(at 113.03 123.825 0)
			(effects
				(font
					(size 1.27 1.27)
					(thickness 0.15)
				)
				(justify left bottom)
				(hide yes)
			)
		)
		(property "Description" "TVS diode array, 15kV, DFN-10, 5 V, 0.5 pF"
			(at 127 127 0)
			(effects
				(font
					(size 1.27 1.27)
				)
				(hide yes)
			)
		)
		(property "MPN" "PESD4USB5U-TTS"
			(at 113.03 121.285 0)
			(effects
				(font
					(size 1.27 1.27)
					(thickness 0.15)
				)
				(justify left bottom)
				(hide yes)
			)
		)
		(property "Manufacturer" "Nexperia"
			(at 113.03 118.745 0)
			(effects
				(font
					(size 1.27 1.27)
					(thickness 0.15)
				)
				(justify left bottom)
				(hide yes)
			)
		)
		(property "Author" "Antmicro"
			(at 113.03 116.205 0)
			(effects
				(font
					(size 1.27 1.27)
					(thickness 0.15)
				)
				(justify left bottom)
				(hide yes)
			)
		)
		(property "License" "Apache-2.0"
			(at 113.03 113.665 0)
			(effects
				(font
					(size 1.27 1.27)
					(thickness 0.15)
				)
				(justify left bottom)
				(hide yes)
			)
		)
		(pin "1"
		)
		(pin "10"
		)
		(pin "2"
		)
		(pin "3"
		)
		(pin "4"
		)
		(pin "5"
		)
		(pin "6"
		)
		(pin "7"
		)
		(pin "8"
		)
		(pin "9"
		)
		(instances
			(project "gmsl-deserializer"
				(path ""
					(reference "D5")
					(unit 1)
				)
			)
		)
	)
	(symbol
		(lib_id "antmicropower:GND")
		(at 342.9 125.73 0)
		(mirror y)
		(unit 1)
		(exclude_from_sim no)
		(in_bom yes)
		(on_board yes)
		(dnp no)
		(property "Reference" "#PWR093"
			(at 334.01 128.27 0)
			(effects
				(font
					(size 1.27 1.27)
					(thickness 0.15)
				)
				(justify left bottom)
				(hide yes)
			)
		)
		(property "Value" "GND"
			(at 342.9 129.54 0)
			(effects
				(font
					(size 1.27 1.27)
					(thickness 0.15)
				)
			)
		)
		(property "Footprint" ""
			(at 334.01 133.35 0)
			(effects
				(font
					(size 1.27 1.27)
					(thickness 0.15)
				)
				(justify left bottom)
				(hide yes)
			)
		)
		(property "Datasheet" ""
			(at 334.01 138.43 0)
			(effects
				(font
					(size 1.27 1.27)
					(thickness 0.15)
				)
				(justify left bottom)
				(hide yes)
			)
		)
		(property "Description" ""
			(at 342.9 125.73 0)
			(effects
				(font
					(size 1.27 1.27)
				)
				(hide yes)
			)
		)
		(property "Author" "Antmicro"
			(at 334.01 133.35 0)
			(effects
				(font
					(size 1.27 1.27)
					(thickness 0.15)
				)
				(justify left bottom)
				(hide yes)
			)
		)
		(property "License" "Apache-2.0"
			(at 334.01 135.89 0)
			(effects
				(font
					(size 1.27 1.27)
					(thickness 0.15)
				)
				(justify left bottom)
				(hide yes)
			)
		)
		(pin "1"
		)
		(instances
			(project "gmsl-deserializer"
				(path ""
					(reference "#PWR093")
					(unit 1)
				)
			)
		)
	)
	(symbol
		(lib_id "antmicroResistors0402:R_80k6_0402")
		(at 121.92 182.88 90)
		(unit 1)
		(exclude_from_sim no)
		(in_bom no)
		(on_board yes)
		(dnp yes)
		(property "Reference" "R48"
			(at 123.825 179.07 90)
			(effects
				(font
					(size 1.27 1.27)
					(thickness 0.15)
				)
				(justify right)
			)
		)
		(property "Value" "R_80k6_0402"
			(at 134.62 162.56 0)
			(effects
				(font
					(size 1.27 1.27)
					(thickness 0.15)
				)
				(justify left bottom)
				(hide yes)
			)
		)
		(property "Footprint" "antmicro-footprints:R_0402_1005Metric"
			(at 137.16 162.56 0)
			(effects
				(font
					(size 1.27 1.27)
					(thickness 0.15)
				)
				(justify left bottom)
				(hide yes)
			)
		)
		(property "Datasheet" "https://www.bourns.com/docs/product-datasheets/cr.pdf"
			(at 139.7 162.56 0)
			(effects
				(font
					(size 1.27 1.27)
					(thickness 0.15)
				)
				(justify left bottom)
				(hide yes)
			)
		)
		(property "Description" "SMD Chip Resistor, 80.6 kohm, ± 1%, 100 mW, 0402 [1005 Metric], Thick Film, Precision"
			(at 121.92 182.88 0)
			(effects
				(font
					(size 1.27 1.27)
				)
				(hide yes)
			)
		)
		(property "MPN" "CR0402-FX-8062GLF"
			(at 142.24 162.56 0)
			(effects
				(font
					(size 1.27 1.27)
					(thickness 0.15)
				)
				(justify left bottom)
				(hide yes)
			)
		)
		(property "Manufacturer" "Bourns"
			(at 144.78 162.56 0)
			(effects
				(font
					(size 1.27 1.27)
					(thickness 0.15)
				)
				(justify left bottom)
				(hide yes)
			)
		)
		(property "License" "Apache-2.0"
			(at 147.32 162.56 0)
			(effects
				(font
					(size 1.27 1.27)
					(thickness 0.15)
				)
				(justify left bottom)
				(hide yes)
			)
		)
		(property "Author" "Antmicro"
			(at 149.86 162.56 0)
			(effects
				(font
					(size 1.27 1.27)
					(thickness 0.15)
				)
				(justify left bottom)
				(hide yes)
			)
		)
		(property "Val" "80k6"
			(at 123.825 181.61 90)
			(effects
				(font
					(size 1.27 1.27)
					(thickness 0.15)
				)
				(justify right)
			)
		)
		(property "Tolerance" "1%"
			(at 132.08 162.56 0)
			(effects
				(font
					(size 1.27 1.27)
				)
				(justify left bottom)
				(hide yes)
			)
		)
		(pin "1"
		)
		(pin "2"
		)
		(instances
			(project "gmsl-deserializer"
				(path ""
					(reference "R48")
					(unit 1)
				)
			)
		)
	)
	(symbol
		(lib_id "antmicroCapacitors0402:C_10n_0402")
		(at 261.62 102.87 90)
		(unit 1)
		(exclude_from_sim no)
		(in_bom yes)
		(on_board yes)
		(dnp no)
		(property "Reference" "C48"
			(at 262.255 98.425 90)
			(effects
				(font
					(size 1.27 1.27)
					(thickness 0.15)
				)
				(justify right)
			)
		)
		(property "Value" "C_10n_0402"
			(at 271.78 82.55 0)
			(effects
				(font
					(size 1.27 1.27)
					(thickness 0.15)
				)
				(justify left bottom)
				(hide yes)
			)
		)
		(property "Footprint" "antmicro-footprints:C_0402_1005Metric"
			(at 274.32 82.55 0)
			(effects
				(font
					(size 1.27 1.27)
					(thickness 0.15)
				)
				(justify left bottom)
				(hide yes)
			)
		)
		(property "Datasheet" "https://www.murata.com/products/productdetail?partno=GRM155R71H103KA88%23"
			(at 276.86 82.55 0)
			(effects
				(font
					(size 1.27 1.27)
					(thickness 0.15)
				)
				(justify left bottom)
				(hide yes)
			)
		)
		(property "Description" "SMD Multilayer Ceramic Capacitor, 10000 pF, 50 V, 0402 [1005 Metric], ± 10%, X7R, GRM Series"
			(at 261.62 102.87 0)
			(effects
				(font
					(size 1.27 1.27)
				)
				(hide yes)
			)
		)
		(property "MPN" "GRM155R71H103KA88D"
			(at 279.4 82.55 0)
			(effects
				(font
					(size 1.27 1.27)
					(thickness 0.15)
				)
				(justify left bottom)
				(hide yes)
			)
		)
		(property "Manufacturer" "Murata"
			(at 281.94 82.55 0)
			(effects
				(font
					(size 1.27 1.27)
					(thickness 0.15)
				)
				(justify left bottom)
				(hide yes)
			)
		)
		(property "License" "Apache-2.0"
			(at 284.48 82.55 0)
			(effects
				(font
					(size 1.27 1.27)
					(thickness 0.15)
				)
				(justify left bottom)
				(hide yes)
			)
		)
		(property "Author" "Antmicro"
			(at 287.02 82.55 0)
			(effects
				(font
					(size 1.27 1.27)
					(thickness 0.15)
				)
				(justify left bottom)
				(hide yes)
			)
		)
		(property "Val" "10n"
			(at 262.255 102.235 90)
			(effects
				(font
					(size 1.27 1.27)
					(thickness 0.15)
				)
				(justify right)
			)
		)
		(property "Voltage" "50V"
			(at 289.56 82.55 0)
			(effects
				(font
					(size 1.27 1.27)
				)
				(justify left bottom)
				(hide yes)
			)
		)
		(property "Dielectric" "X7R"
			(at 292.1 82.55 0)
			(effects
				(font
					(size 1.27 1.27)
				)
				(justify left bottom)
				(hide yes)
			)
		)
		(pin "1"
		)
		(pin "2"
		)
		(instances
			(project "gmsl-deserializer"
				(path ""
					(reference "C48")
					(unit 1)
				)
			)
		)
	)
	(symbol
		(lib_id "antmicropower:+1V2")
		(at 370.84 109.22 0)
		(unit 1)
		(exclude_from_sim no)
		(in_bom yes)
		(on_board yes)
		(dnp no)
		(property "Reference" "#PWR099"
			(at 370.84 113.03 0)
			(effects
				(font
					(size 1.27 1.27)
				)
				(hide yes)
			)
		)
		(property "Value" "+1V2"
			(at 370.205 105.41 0)
			(effects
				(font
					(size 1.27 1.27)
				)
			)
		)
		(property "Footprint" ""
			(at 370.84 109.22 0)
			(effects
				(font
					(size 1.27 1.27)
				)
				(hide yes)
			)
		)
		(property "Datasheet" ""
			(at 370.84 109.22 0)
			(effects
				(font
					(size 1.27 1.27)
				)
				(hide yes)
			)
		)
		(property "Description" ""
			(at 370.84 109.22 0)
			(effects
				(font
					(size 1.27 1.27)
				)
				(hide yes)
			)
		)
		(pin "1"
		)
		(instances
			(project "gmsl-deserializer"
				(path ""
					(reference "#PWR099")
					(unit 1)
				)
			)
		)
	)
	(symbol
		(lib_id "antmicropower:GND")
		(at 251.46 104.14 0)
		(unit 1)
		(exclude_from_sim no)
		(in_bom yes)
		(on_board yes)
		(dnp no)
		(property "Reference" "#PWR085"
			(at 260.35 106.68 0)
			(effects
				(font
					(size 1.27 1.27)
					(thickness 0.15)
				)
				(justify left bottom)
				(hide yes)
			)
		)
		(property "Value" "GND"
			(at 251.46 107.95 0)
			(effects
				(font
					(size 1.27 1.27)
					(thickness 0.15)
				)
			)
		)
		(property "Footprint" ""
			(at 260.35 111.76 0)
			(effects
				(font
					(size 1.27 1.27)
					(thickness 0.15)
				)
				(justify left bottom)
				(hide yes)
			)
		)
		(property "Datasheet" ""
			(at 260.35 116.84 0)
			(effects
				(font
					(size 1.27 1.27)
					(thickness 0.15)
				)
				(justify left bottom)
				(hide yes)
			)
		)
		(property "Description" ""
			(at 251.46 104.14 0)
			(effects
				(font
					(size 1.27 1.27)
				)
				(hide yes)
			)
		)
		(property "Author" "Antmicro"
			(at 260.35 111.76 0)
			(effects
				(font
					(size 1.27 1.27)
					(thickness 0.15)
				)
				(justify left bottom)
				(hide yes)
			)
		)
		(property "License" "Apache-2.0"
			(at 260.35 114.3 0)
			(effects
				(font
					(size 1.27 1.27)
					(thickness 0.15)
				)
				(justify left bottom)
				(hide yes)
			)
		)
		(pin "1"
		)
		(instances
			(project "gmsl-deserializer"
				(path ""
					(reference "#PWR085")
					(unit 1)
				)
			)
		)
	)
	(symbol
		(lib_id "antmicropower:GND")
		(at 279.4 200.66 0)
		(unit 1)
		(exclude_from_sim no)
		(in_bom yes)
		(on_board yes)
		(dnp no)
		(property "Reference" "#PWR091"
			(at 288.29 203.2 0)
			(effects
				(font
					(size 1.27 1.27)
					(thickness 0.15)
				)
				(justify left bottom)
				(hide yes)
			)
		)
		(property "Value" "GND"
			(at 279.4 204.47 0)
			(effects
				(font
					(size 1.27 1.27)
					(thickness 0.15)
				)
			)
		)
		(property "Footprint" ""
			(at 288.29 208.28 0)
			(effects
				(font
					(size 1.27 1.27)
					(thickness 0.15)
				)
				(justify left bottom)
				(hide yes)
			)
		)
		(property "Datasheet" ""
			(at 288.29 213.36 0)
			(effects
				(font
					(size 1.27 1.27)
					(thickness 0.15)
				)
				(justify left bottom)
				(hide yes)
			)
		)
		(property "Description" ""
			(at 279.4 200.66 0)
			(effects
				(font
					(size 1.27 1.27)
				)
				(hide yes)
			)
		)
		(property "Author" "Antmicro"
			(at 288.29 208.28 0)
			(effects
				(font
					(size 1.27 1.27)
					(thickness 0.15)
				)
				(justify left bottom)
				(hide yes)
			)
		)
		(property "License" "Apache-2.0"
			(at 288.29 210.82 0)
			(effects
				(font
					(size 1.27 1.27)
					(thickness 0.15)
				)
				(justify left bottom)
				(hide yes)
			)
		)
		(pin "1"
		)
		(instances
			(project "gmsl-deserializer"
				(path ""
					(reference "#PWR091")
					(unit 1)
				)
			)
		)
	)
	(symbol
		(lib_id "antmicroCapacitors0402:C_10u_0402")
		(at 227.33 200.66 90)
		(unit 1)
		(exclude_from_sim no)
		(in_bom yes)
		(on_board yes)
		(dnp no)
		(property "Reference" "C38"
			(at 227.965 196.215 90)
			(effects
				(font
					(size 1.27 1.27)
					(thickness 0.15)
				)
				(justify right)
			)
		)
		(property "Value" "C_10u_0402"
			(at 237.49 180.34 0)
			(effects
				(font
					(size 1.27 1.27)
					(thickness 0.15)
				)
				(justify left bottom)
				(hide yes)
			)
		)
		(property "Footprint" "antmicro-footprints:C_0402_1005Metric"
			(at 240.03 180.34 0)
			(effects
				(font
					(size 1.27 1.27)
					(thickness 0.15)
				)
				(justify left bottom)
				(hide yes)
			)
		)
		(property "Datasheet" "https://www.yageo.com/en/Chart/Download/pdf/CC0402MRX5R5BB106"
			(at 242.57 180.34 0)
			(effects
				(font
					(size 1.27 1.27)
					(thickness 0.15)
				)
				(justify left bottom)
				(hide yes)
			)
		)
		(property "Description" "SMD Multilayer Ceramic Capacitor, 10 µF, 6.3 V, 0402 [1005 Metric], ± 20%, X5R, CC Series"
			(at 227.33 200.66 0)
			(effects
				(font
					(size 1.27 1.27)
				)
				(hide yes)
			)
		)
		(property "MPN" "CC0402MRX5R5BB106"
			(at 245.11 180.34 0)
			(effects
				(font
					(size 1.27 1.27)
					(thickness 0.15)
				)
				(justify left bottom)
				(hide yes)
			)
		)
		(property "Manufacturer" "YAGEO"
			(at 247.65 180.34 0)
			(effects
				(font
					(size 1.27 1.27)
					(thickness 0.15)
				)
				(justify left bottom)
				(hide yes)
			)
		)
		(property "License" "Apache-2.0"
			(at 250.19 180.34 0)
			(effects
				(font
					(size 1.27 1.27)
					(thickness 0.15)
				)
				(justify left bottom)
				(hide yes)
			)
		)
		(property "Author" "Antmicro"
			(at 252.73 180.34 0)
			(effects
				(font
					(size 1.27 1.27)
					(thickness 0.15)
				)
				(justify left bottom)
				(hide yes)
			)
		)
		(property "Val" "10u"
			(at 227.965 200.025 90)
			(effects
				(font
					(size 1.27 1.27)
					(thickness 0.15)
				)
				(justify right)
			)
		)
		(property "Voltage" ""
			(at 255.27 180.34 0)
			(effects
				(font
					(size 1.27 1.27)
				)
				(justify left bottom)
				(hide yes)
			)
		)
		(property "Dielectric" ""
			(at 257.81 180.34 0)
			(effects
				(font
					(size 1.27 1.27)
				)
				(justify left bottom)
				(hide yes)
			)
		)
		(pin "1"
		)
		(pin "2"
		)
		(instances
			(project "gmsl-deserializer"
				(path ""
					(reference "C38")
					(unit 1)
				)
			)
		)
	)
	(symbol
		(lib_id "antmicropower:GND")
		(at 66.04 121.92 0)
		(unit 1)
		(exclude_from_sim no)
		(in_bom yes)
		(on_board yes)
		(dnp no)
		(property "Reference" "#PWR068"
			(at 74.93 124.46 0)
			(effects
				(font
					(size 1.27 1.27)
					(thickness 0.15)
				)
				(justify left bottom)
				(hide yes)
			)
		)
		(property "Value" "GND"
			(at 66.04 125.73 0)
			(effects
				(font
					(size 1.27 1.27)
					(thickness 0.15)
				)
			)
		)
		(property "Footprint" ""
			(at 74.93 129.54 0)
			(effects
				(font
					(size 1.27 1.27)
					(thickness 0.15)
				)
				(justify left bottom)
				(hide yes)
			)
		)
		(property "Datasheet" ""
			(at 74.93 134.62 0)
			(effects
				(font
					(size 1.27 1.27)
					(thickness 0.15)
				)
				(justify left bottom)
				(hide yes)
			)
		)
		(property "Description" ""
			(at 66.04 121.92 0)
			(effects
				(font
					(size 1.27 1.27)
				)
				(hide yes)
			)
		)
		(property "Author" "Antmicro"
			(at 74.93 129.54 0)
			(effects
				(font
					(size 1.27 1.27)
					(thickness 0.15)
				)
				(justify left bottom)
				(hide yes)
			)
		)
		(property "License" "Apache-2.0"
			(at 74.93 132.08 0)
			(effects
				(font
					(size 1.27 1.27)
					(thickness 0.15)
				)
				(justify left bottom)
				(hide yes)
			)
		)
		(pin "1"
		)
		(instances
			(project "gmsl-deserializer"
				(path ""
					(reference "#PWR068")
					(unit 1)
				)
			)
		)
	)
	(symbol
		(lib_id "antmicropower:+1V8")
		(at 370.84 88.9 0)
		(unit 1)
		(exclude_from_sim no)
		(in_bom yes)
		(on_board yes)
		(dnp no)
		(property "Reference" "#PWR098"
			(at 386.08 91.44 0)
			(effects
				(font
					(size 1.27 1.27)
					(thickness 0.15)
				)
				(justify left bottom)
				(hide yes)
			)
		)
		(property "Value" "+1V8"
			(at 370.84 85.09 0)
			(effects
				(font
					(size 1.27 1.27)
					(thickness 0.15)
				)
			)
		)
		(property "Footprint" ""
			(at 386.08 96.52 0)
			(effects
				(font
					(size 1.27 1.27)
					(thickness 0.15)
				)
				(justify left bottom)
				(hide yes)
			)
		)
		(property "Datasheet" ""
			(at 386.08 99.06 0)
			(effects
				(font
					(size 1.27 1.27)
					(thickness 0.15)
				)
				(justify left bottom)
				(hide yes)
			)
		)
		(property "Description" ""
			(at 370.84 88.9 0)
			(effects
				(font
					(size 1.27 1.27)
				)
				(hide yes)
			)
		)
		(property "Author" "Antmicro"
			(at 386.08 96.52 0)
			(effects
				(font
					(size 1.27 1.27)
					(thickness 0.15)
				)
				(justify left bottom)
				(hide yes)
			)
		)
		(property "License" "Apache-2.0"
			(at 386.08 99.06 0)
			(effects
				(font
					(size 1.27 1.27)
					(thickness 0.15)
				)
				(justify left bottom)
				(hide yes)
			)
		)
		(pin "1"
		)
		(instances
			(project "gmsl-deserializer"
				(path ""
					(reference "#PWR098")
					(unit 1)
				)
			)
		)
	)
	(symbol
		(lib_id "antmicroCapacitors0402:C_100n_0402")
		(at 353.06 124.46 90)
		(unit 1)
		(exclude_from_sim no)
		(in_bom yes)
		(on_board yes)
		(dnp no)
		(property "Reference" "C53"
			(at 353.695 120.015 90)
			(effects
				(font
					(size 1.27 1.27)
					(thickness 0.15)
				)
				(justify right)
			)
		)
		(property "Value" "C_100n_0402"
			(at 363.22 104.14 0)
			(effects
				(font
					(size 1.27 1.27)
					(thickness 0.15)
				)
				(justify left bottom)
				(hide yes)
			)
		)
		(property "Footprint" "antmicro-footprints:C_0402_1005Metric"
			(at 365.76 104.14 0)
			(effects
				(font
					(size 1.27 1.27)
					(thickness 0.15)
				)
				(justify left bottom)
				(hide yes)
			)
		)
		(property "Datasheet" "https://www.murata.com/products/productdetail?partno=GRM155R61H104KE14%23"
			(at 368.3 104.14 0)
			(effects
				(font
					(size 1.27 1.27)
					(thickness 0.15)
				)
				(justify left bottom)
				(hide yes)
			)
		)
		(property "Description" "SMD Multilayer Ceramic Capacitor, 0.1 µF, 50 V, 0402 [1005 Metric], ± 10%, X5R, GRM Series"
			(at 353.06 124.46 0)
			(effects
				(font
					(size 1.27 1.27)
				)
				(hide yes)
			)
		)
		(property "MPN" "GRM155R61H104KE14D"
			(at 370.84 104.14 0)
			(effects
				(font
					(size 1.27 1.27)
					(thickness 0.15)
				)
				(justify left bottom)
				(hide yes)
			)
		)
		(property "Manufacturer" "Murata"
			(at 373.38 104.14 0)
			(effects
				(font
					(size 1.27 1.27)
					(thickness 0.15)
				)
				(justify left bottom)
				(hide yes)
			)
		)
		(property "License" "Apache-2.0"
			(at 375.92 104.14 0)
			(effects
				(font
					(size 1.27 1.27)
					(thickness 0.15)
				)
				(justify left bottom)
				(hide yes)
			)
		)
		(property "Author" "Antmicro"
			(at 378.46 104.14 0)
			(effects
				(font
					(size 1.27 1.27)
					(thickness 0.15)
				)
				(justify left bottom)
				(hide yes)
			)
		)
		(property "Val" "100n"
			(at 353.695 123.825 90)
			(effects
				(font
					(size 1.27 1.27)
					(thickness 0.15)
				)
				(justify right)
			)
		)
		(property "Voltage" "50V"
			(at 381 104.14 0)
			(effects
				(font
					(size 1.27 1.27)
				)
				(justify left bottom)
				(hide yes)
			)
		)
		(property "Dielectric" "X5R"
			(at 383.54 104.14 0)
			(effects
				(font
					(size 1.27 1.27)
				)
				(justify left bottom)
				(hide yes)
			)
		)
		(pin "1"
		)
		(pin "2"
		)
		(instances
			(project "gmsl-deserializer"
				(path ""
					(reference "C53")
					(unit 1)
				)
			)
		)
	)
	(symbol
		(lib_id "antmicroResistors0402:R_80k6_0402")
		(at 162.56 182.88 90)
		(unit 1)
		(exclude_from_sim no)
		(in_bom no)
		(on_board yes)
		(dnp yes)
		(property "Reference" "R50"
			(at 164.465 179.07 90)
			(effects
				(font
					(size 1.27 1.27)
					(thickness 0.15)
				)
				(justify right)
			)
		)
		(property "Value" "R_80k6_0402"
			(at 175.26 162.56 0)
			(effects
				(font
					(size 1.27 1.27)
					(thickness 0.15)
				)
				(justify left bottom)
				(hide yes)
			)
		)
		(property "Footprint" "antmicro-footprints:R_0402_1005Metric"
			(at 177.8 162.56 0)
			(effects
				(font
					(size 1.27 1.27)
					(thickness 0.15)
				)
				(justify left bottom)
				(hide yes)
			)
		)
		(property "Datasheet" "https://www.bourns.com/docs/product-datasheets/cr.pdf"
			(at 180.34 162.56 0)
			(effects
				(font
					(size 1.27 1.27)
					(thickness 0.15)
				)
				(justify left bottom)
				(hide yes)
			)
		)
		(property "Description" "SMD Chip Resistor, 80.6 kohm, ± 1%, 100 mW, 0402 [1005 Metric], Thick Film, Precision"
			(at 162.56 182.88 0)
			(effects
				(font
					(size 1.27 1.27)
				)
				(hide yes)
			)
		)
		(property "MPN" "CR0402-FX-8062GLF"
			(at 182.88 162.56 0)
			(effects
				(font
					(size 1.27 1.27)
					(thickness 0.15)
				)
				(justify left bottom)
				(hide yes)
			)
		)
		(property "Manufacturer" "Bourns"
			(at 185.42 162.56 0)
			(effects
				(font
					(size 1.27 1.27)
					(thickness 0.15)
				)
				(justify left bottom)
				(hide yes)
			)
		)
		(property "License" "Apache-2.0"
			(at 187.96 162.56 0)
			(effects
				(font
					(size 1.27 1.27)
					(thickness 0.15)
				)
				(justify left bottom)
				(hide yes)
			)
		)
		(property "Author" "Antmicro"
			(at 190.5 162.56 0)
			(effects
				(font
					(size 1.27 1.27)
					(thickness 0.15)
				)
				(justify left bottom)
				(hide yes)
			)
		)
		(property "Val" "80k6"
			(at 164.465 181.61 90)
			(effects
				(font
					(size 1.27 1.27)
					(thickness 0.15)
				)
				(justify right)
			)
		)
		(property "Tolerance" "1%"
			(at 172.72 162.56 0)
			(effects
				(font
					(size 1.27 1.27)
				)
				(justify left bottom)
				(hide yes)
			)
		)
		(pin "1"
		)
		(pin "2"
		)
		(instances
			(project "gmsl-deserializer"
				(path ""
					(reference "R50")
					(unit 1)
				)
			)
		)
	)
	(symbol
		(lib_id "antmicropower:GND")
		(at 242.57 104.14 0)
		(unit 1)
		(exclude_from_sim no)
		(in_bom yes)
		(on_board yes)
		(dnp no)
		(property "Reference" "#PWR082"
			(at 251.46 106.68 0)
			(effects
				(font
					(size 1.27 1.27)
					(thickness 0.15)
				)
				(justify left bottom)
				(hide yes)
			)
		)
		(property "Value" "GND"
			(at 242.57 107.95 0)
			(effects
				(font
					(size 1.27 1.27)
					(thickness 0.15)
				)
			)
		)
		(property "Footprint" ""
			(at 251.46 111.76 0)
			(effects
				(font
					(size 1.27 1.27)
					(thickness 0.15)
				)
				(justify left bottom)
				(hide yes)
			)
		)
		(property "Datasheet" ""
			(at 251.46 116.84 0)
			(effects
				(font
					(size 1.27 1.27)
					(thickness 0.15)
				)
				(justify left bottom)
				(hide yes)
			)
		)
		(property "Description" ""
			(at 242.57 104.14 0)
			(effects
				(font
					(size 1.27 1.27)
				)
				(hide yes)
			)
		)
		(property "Author" "Antmicro"
			(at 251.46 111.76 0)
			(effects
				(font
					(size 1.27 1.27)
					(thickness 0.15)
				)
				(justify left bottom)
				(hide yes)
			)
		)
		(property "License" "Apache-2.0"
			(at 251.46 114.3 0)
			(effects
				(font
					(size 1.27 1.27)
					(thickness 0.15)
				)
				(justify left bottom)
				(hide yes)
			)
		)
		(pin "1"
		)
		(instances
			(project "gmsl-deserializer"
				(path ""
					(reference "#PWR082")
					(unit 1)
				)
			)
		)
	)
	(symbol
		(lib_id "antmicropower:GND")
		(at 66.04 106.68 0)
		(unit 1)
		(exclude_from_sim no)
		(in_bom yes)
		(on_board yes)
		(dnp no)
		(property "Reference" "#PWR066"
			(at 74.93 109.22 0)
			(effects
				(font
					(size 1.27 1.27)
					(thickness 0.15)
				)
				(justify left bottom)
				(hide yes)
			)
		)
		(property "Value" "GND"
			(at 66.04 110.49 0)
			(effects
				(font
					(size 1.27 1.27)
					(thickness 0.15)
				)
			)
		)
		(property "Footprint" ""
			(at 74.93 114.3 0)
			(effects
				(font
					(size 1.27 1.27)
					(thickness 0.15)
				)
				(justify left bottom)
				(hide yes)
			)
		)
		(property "Datasheet" ""
			(at 74.93 119.38 0)
			(effects
				(font
					(size 1.27 1.27)
					(thickness 0.15)
				)
				(justify left bottom)
				(hide yes)
			)
		)
		(property "Description" ""
			(at 66.04 106.68 0)
			(effects
				(font
					(size 1.27 1.27)
				)
				(hide yes)
			)
		)
		(property "Author" "Antmicro"
			(at 74.93 114.3 0)
			(effects
				(font
					(size 1.27 1.27)
					(thickness 0.15)
				)
				(justify left bottom)
				(hide yes)
			)
		)
		(property "License" "Apache-2.0"
			(at 74.93 116.84 0)
			(effects
				(font
					(size 1.27 1.27)
					(thickness 0.15)
				)
				(justify left bottom)
				(hide yes)
			)
		)
		(pin "1"
		)
		(instances
			(project "gmsl-deserializer"
				(path ""
					(reference "#PWR066")
					(unit 1)
				)
			)
		)
	)
	(symbol
		(lib_id "antmicropower:GND")
		(at 227.33 201.93 0)
		(unit 1)
		(exclude_from_sim no)
		(in_bom yes)
		(on_board yes)
		(dnp no)
		(property "Reference" "#PWR078"
			(at 236.22 204.47 0)
			(effects
				(font
					(size 1.27 1.27)
					(thickness 0.15)
				)
				(justify left bottom)
				(hide yes)
			)
		)
		(property "Value" "GND"
			(at 227.33 205.74 0)
			(effects
				(font
					(size 1.27 1.27)
					(thickness 0.15)
				)
			)
		)
		(property "Footprint" ""
			(at 236.22 209.55 0)
			(effects
				(font
					(size 1.27 1.27)
					(thickness 0.15)
				)
				(justify left bottom)
				(hide yes)
			)
		)
		(property "Datasheet" ""
			(at 236.22 214.63 0)
			(effects
				(font
					(size 1.27 1.27)
					(thickness 0.15)
				)
				(justify left bottom)
				(hide yes)
			)
		)
		(property "Description" ""
			(at 227.33 201.93 0)
			(effects
				(font
					(size 1.27 1.27)
				)
				(hide yes)
			)
		)
		(property "Author" "Antmicro"
			(at 236.22 209.55 0)
			(effects
				(font
					(size 1.27 1.27)
					(thickness 0.15)
				)
				(justify left bottom)
				(hide yes)
			)
		)
		(property "License" "Apache-2.0"
			(at 236.22 212.09 0)
			(effects
				(font
					(size 1.27 1.27)
					(thickness 0.15)
				)
				(justify left bottom)
				(hide yes)
			)
		)
		(pin "1"
		)
		(instances
			(project "gmsl-deserializer"
				(path ""
					(reference "#PWR078")
					(unit 1)
				)
			)
		)
	)
	(symbol
		(lib_id "antmicropower:GND")
		(at 361.95 125.73 0)
		(mirror y)
		(unit 1)
		(exclude_from_sim no)
		(in_bom yes)
		(on_board yes)
		(dnp no)
		(property "Reference" "#PWR097"
			(at 353.06 128.27 0)
			(effects
				(font
					(size 1.27 1.27)
					(thickness 0.15)
				)
				(justify left bottom)
				(hide yes)
			)
		)
		(property "Value" "GND"
			(at 361.95 129.54 0)
			(effects
				(font
					(size 1.27 1.27)
					(thickness 0.15)
				)
			)
		)
		(property "Footprint" ""
			(at 353.06 133.35 0)
			(effects
				(font
					(size 1.27 1.27)
					(thickness 0.15)
				)
				(justify left bottom)
				(hide yes)
			)
		)
		(property "Datasheet" ""
			(at 353.06 138.43 0)
			(effects
				(font
					(size 1.27 1.27)
					(thickness 0.15)
				)
				(justify left bottom)
				(hide yes)
			)
		)
		(property "Description" ""
			(at 361.95 125.73 0)
			(effects
				(font
					(size 1.27 1.27)
				)
				(hide yes)
			)
		)
		(property "Author" "Antmicro"
			(at 353.06 133.35 0)
			(effects
				(font
					(size 1.27 1.27)
					(thickness 0.15)
				)
				(justify left bottom)
				(hide yes)
			)
		)
		(property "License" "Apache-2.0"
			(at 353.06 135.89 0)
			(effects
				(font
					(size 1.27 1.27)
					(thickness 0.15)
				)
				(justify left bottom)
				(hide yes)
			)
		)
		(pin "1"
		)
		(instances
			(project "gmsl-deserializer"
				(path ""
					(reference "#PWR097")
					(unit 1)
				)
			)
		)
	)
	(symbol
		(lib_id "antmicroCapacitors0402:C_100n_0402")
		(at 251.46 102.87 90)
		(unit 1)
		(exclude_from_sim no)
		(in_bom yes)
		(on_board yes)
		(dnp no)
		(property "Reference" "C45"
			(at 252.095 98.425 90)
			(effects
				(font
					(size 1.27 1.27)
					(thickness 0.15)
				)
				(justify right)
			)
		)
		(property "Value" "C_100n_0402"
			(at 261.62 82.55 0)
			(effects
				(font
					(size 1.27 1.27)
					(thickness 0.15)
				)
				(justify left bottom)
				(hide yes)
			)
		)
		(property "Footprint" "antmicro-footprints:C_0402_1005Metric"
			(at 264.16 82.55 0)
			(effects
				(font
					(size 1.27 1.27)
					(thickness 0.15)
				)
				(justify left bottom)
				(hide yes)
			)
		)
		(property "Datasheet" "https://www.murata.com/products/productdetail?partno=GRM155R61H104KE14%23"
			(at 266.7 82.55 0)
			(effects
				(font
					(size 1.27 1.27)
					(thickness 0.15)
				)
				(justify left bottom)
				(hide yes)
			)
		)
		(property "Description" "SMD Multilayer Ceramic Capacitor, 0.1 µF, 50 V, 0402 [1005 Metric], ± 10%, X5R, GRM Series"
			(at 251.46 102.87 0)
			(effects
				(font
					(size 1.27 1.27)
				)
				(hide yes)
			)
		)
		(property "MPN" "GRM155R61H104KE14D"
			(at 269.24 82.55 0)
			(effects
				(font
					(size 1.27 1.27)
					(thickness 0.15)
				)
				(justify left bottom)
				(hide yes)
			)
		)
		(property "Manufacturer" "Murata"
			(at 271.78 82.55 0)
			(effects
				(font
					(size 1.27 1.27)
					(thickness 0.15)
				)
				(justify left bottom)
				(hide yes)
			)
		)
		(property "License" "Apache-2.0"
			(at 274.32 82.55 0)
			(effects
				(font
					(size 1.27 1.27)
					(thickness 0.15)
				)
				(justify left bottom)
				(hide yes)
			)
		)
		(property "Author" "Antmicro"
			(at 276.86 82.55 0)
			(effects
				(font
					(size 1.27 1.27)
					(thickness 0.15)
				)
				(justify left bottom)
				(hide yes)
			)
		)
		(property "Val" "100n"
			(at 252.095 102.235 90)
			(effects
				(font
					(size 1.27 1.27)
					(thickness 0.15)
				)
				(justify right)
			)
		)
		(property "Voltage" "50V"
			(at 279.4 82.55 0)
			(effects
				(font
					(size 1.27 1.27)
				)
				(justify left bottom)
				(hide yes)
			)
		)
		(property "Dielectric" "X5R"
			(at 281.94 82.55 0)
			(effects
				(font
					(size 1.27 1.27)
				)
				(justify left bottom)
				(hide yes)
			)
		)
		(pin "1"
		)
		(pin "2"
		)
		(instances
			(project "gmsl-deserializer"
				(path ""
					(reference "C45")
					(unit 1)
				)
			)
		)
	)
	(symbol
		(lib_id "antmicropower:GND")
		(at 113.03 129.54 0)
		(unit 1)
		(exclude_from_sim no)
		(in_bom yes)
		(on_board yes)
		(dnp no)
		(property "Reference" "#PWR071"
			(at 121.92 132.08 0)
			(effects
				(font
					(size 1.27 1.27)
					(thickness 0.15)
				)
				(justify left bottom)
				(hide yes)
			)
		)
		(property "Value" "GND"
			(at 113.03 133.35 0)
			(effects
				(font
					(size 1.27 1.27)
					(thickness 0.15)
				)
			)
		)
		(property "Footprint" ""
			(at 121.92 137.16 0)
			(effects
				(font
					(size 1.27 1.27)
					(thickness 0.15)
				)
				(justify left bottom)
				(hide yes)
			)
		)
		(property "Datasheet" ""
			(at 121.92 142.24 0)
			(effects
				(font
					(size 1.27 1.27)
					(thickness 0.15)
				)
				(justify left bottom)
				(hide yes)
			)
		)
		(property "Description" ""
			(at 113.03 129.54 0)
			(effects
				(font
					(size 1.27 1.27)
				)
				(hide yes)
			)
		)
		(property "Author" "Antmicro"
			(at 121.92 137.16 0)
			(effects
				(font
					(size 1.27 1.27)
					(thickness 0.15)
				)
				(justify left bottom)
				(hide yes)
			)
		)
		(property "License" "Apache-2.0"
			(at 121.92 139.7 0)
			(effects
				(font
					(size 1.27 1.27)
					(thickness 0.15)
				)
				(justify left bottom)
				(hide yes)
			)
		)
		(pin "1"
		)
		(instances
			(project "gmsl-deserializer"
				(path ""
					(reference "#PWR071")
					(unit 1)
				)
			)
		)
	)
	(symbol
		(lib_id "antmicroCapacitors0402:C_100n_0402")
		(at 232.41 121.92 90)
		(unit 1)
		(exclude_from_sim no)
		(in_bom yes)
		(on_board yes)
		(dnp no)
		(property "Reference" "C40"
			(at 233.045 117.475 90)
			(effects
				(font
					(size 1.27 1.27)
					(thickness 0.15)
				)
				(justify right)
			)
		)
		(property "Value" "C_100n_0402"
			(at 242.57 101.6 0)
			(effects
				(font
					(size 1.27 1.27)
					(thickness 0.15)
				)
				(justify left bottom)
				(hide yes)
			)
		)
		(property "Footprint" "antmicro-footprints:C_0402_1005Metric"
			(at 245.11 101.6 0)
			(effects
				(font
					(size 1.27 1.27)
					(thickness 0.15)
				)
				(justify left bottom)
				(hide yes)
			)
		)
		(property "Datasheet" "https://www.murata.com/products/productdetail?partno=GRM155R61H104KE14%23"
			(at 247.65 101.6 0)
			(effects
				(font
					(size 1.27 1.27)
					(thickness 0.15)
				)
				(justify left bottom)
				(hide yes)
			)
		)
		(property "Description" "SMD Multilayer Ceramic Capacitor, 0.1 µF, 50 V, 0402 [1005 Metric], ± 10%, X5R, GRM Series"
			(at 232.41 121.92 0)
			(effects
				(font
					(size 1.27 1.27)
				)
				(hide yes)
			)
		)
		(property "MPN" "GRM155R61H104KE14D"
			(at 250.19 101.6 0)
			(effects
				(font
					(size 1.27 1.27)
					(thickness 0.15)
				)
				(justify left bottom)
				(hide yes)
			)
		)
		(property "Manufacturer" "Murata"
			(at 252.73 101.6 0)
			(effects
				(font
					(size 1.27 1.27)
					(thickness 0.15)
				)
				(justify left bottom)
				(hide yes)
			)
		)
		(property "License" "Apache-2.0"
			(at 255.27 101.6 0)
			(effects
				(font
					(size 1.27 1.27)
					(thickness 0.15)
				)
				(justify left bottom)
				(hide yes)
			)
		)
		(property "Author" "Antmicro"
			(at 257.81 101.6 0)
			(effects
				(font
					(size 1.27 1.27)
					(thickness 0.15)
				)
				(justify left bottom)
				(hide yes)
			)
		)
		(property "Val" "100n"
			(at 233.045 121.285 90)
			(effects
				(font
					(size 1.27 1.27)
					(thickness 0.15)
				)
				(justify right)
			)
		)
		(property "Voltage" "50V"
			(at 260.35 101.6 0)
			(effects
				(font
					(size 1.27 1.27)
				)
				(justify left bottom)
				(hide yes)
			)
		)
		(property "Dielectric" "X5R"
			(at 262.89 101.6 0)
			(effects
				(font
					(size 1.27 1.27)
				)
				(justify left bottom)
				(hide yes)
			)
		)
		(pin "1"
		)
		(pin "2"
		)
		(instances
			(project "gmsl-deserializer"
				(path ""
					(reference "C40")
					(unit 1)
				)
			)
		)
	)
	(symbol
		(lib_id "antmicroResistors0402:R_402R_0402")
		(at 265.43 205.74 90)
		(unit 1)
		(exclude_from_sim no)
		(in_bom yes)
		(on_board yes)
		(dnp no)
		(property "Reference" "R54"
			(at 267.335 201.93 90)
			(effects
				(font
					(size 1.27 1.27)
					(thickness 0.15)
				)
				(justify right)
			)
		)
		(property "Value" "R_402R_0402"
			(at 278.13 185.42 0)
			(effects
				(font
					(size 1.27 1.27)
					(thickness 0.15)
				)
				(justify left bottom)
				(hide yes)
			)
		)
		(property "Footprint" "antmicro-footprints:R_0402_1005Metric"
			(at 280.67 185.42 0)
			(effects
				(font
					(size 1.27 1.27)
					(thickness 0.15)
				)
				(justify left bottom)
				(hide yes)
			)
		)
		(property "Datasheet" "https://www.mouser.com/datasheet/2/54/cr-1858361.pdf"
			(at 283.21 185.42 0)
			(effects
				(font
					(size 1.27 1.27)
					(thickness 0.15)
				)
				(justify left bottom)
				(hide yes)
			)
		)
		(property "Description" "SMD Chip Resistor, 402 ohm, ± 1%, 63 mW, 0402 [1005 Metric], Thick Film, General Purpose"
			(at 265.43 205.74 0)
			(effects
				(font
					(size 1.27 1.27)
				)
				(hide yes)
			)
		)
		(property "MPN" "CR0402-FX-4020GLF"
			(at 285.75 185.42 0)
			(effects
				(font
					(size 1.27 1.27)
					(thickness 0.15)
				)
				(justify left bottom)
				(hide yes)
			)
		)
		(property "Manufacturer" "Bourns"
			(at 288.29 185.42 0)
			(effects
				(font
					(size 1.27 1.27)
					(thickness 0.15)
				)
				(justify left bottom)
				(hide yes)
			)
		)
		(property "License" "Apache-2.0"
			(at 290.83 185.42 0)
			(effects
				(font
					(size 1.27 1.27)
					(thickness 0.15)
				)
				(justify left bottom)
				(hide yes)
			)
		)
		(property "Author" "Antmicro"
			(at 293.37 185.42 0)
			(effects
				(font
					(size 1.27 1.27)
					(thickness 0.15)
				)
				(justify left bottom)
				(hide yes)
			)
		)
		(property "Val" "402R"
			(at 267.335 204.47 90)
			(effects
				(font
					(size 1.27 1.27)
					(thickness 0.15)
				)
				(justify right)
			)
		)
		(property "Tolerance" "1%"
			(at 275.59 185.42 0)
			(effects
				(font
					(size 1.27 1.27)
				)
				(justify left bottom)
				(hide yes)
			)
		)
		(pin "1"
		)
		(pin "2"
		)
		(instances
			(project "gmsl-deserializer"
				(path ""
					(reference "R54")
					(unit 1)
				)
			)
		)
	)
	(symbol
		(lib_id "antmicroCapacitors0402:C_10n_0402")
		(at 342.9 124.46 90)
		(unit 1)
		(exclude_from_sim no)
		(in_bom yes)
		(on_board yes)
		(dnp no)
		(property "Reference" "C51"
			(at 343.535 120.015 90)
			(effects
				(font
					(size 1.27 1.27)
					(thickness 0.15)
				)
				(justify right)
			)
		)
		(property "Value" "C_10n_0402"
			(at 353.06 104.14 0)
			(effects
				(font
					(size 1.27 1.27)
					(thickness 0.15)
				)
				(justify left bottom)
				(hide yes)
			)
		)
		(property "Footprint" "antmicro-footprints:C_0402_1005Metric"
			(at 355.6 104.14 0)
			(effects
				(font
					(size 1.27 1.27)
					(thickness 0.15)
				)
				(justify left bottom)
				(hide yes)
			)
		)
		(property "Datasheet" "https://www.murata.com/products/productdetail?partno=GRM155R71H103KA88%23"
			(at 358.14 104.14 0)
			(effects
				(font
					(size 1.27 1.27)
					(thickness 0.15)
				)
				(justify left bottom)
				(hide yes)
			)
		)
		(property "Description" "SMD Multilayer Ceramic Capacitor, 10000 pF, 50 V, 0402 [1005 Metric], ± 10%, X7R, GRM Series"
			(at 342.9 124.46 0)
			(effects
				(font
					(size 1.27 1.27)
				)
				(hide yes)
			)
		)
		(property "MPN" "GRM155R71H103KA88D"
			(at 360.68 104.14 0)
			(effects
				(font
					(size 1.27 1.27)
					(thickness 0.15)
				)
				(justify left bottom)
				(hide yes)
			)
		)
		(property "Manufacturer" "Murata"
			(at 363.22 104.14 0)
			(effects
				(font
					(size 1.27 1.27)
					(thickness 0.15)
				)
				(justify left bottom)
				(hide yes)
			)
		)
		(property "License" "Apache-2.0"
			(at 365.76 104.14 0)
			(effects
				(font
					(size 1.27 1.27)
					(thickness 0.15)
				)
				(justify left bottom)
				(hide yes)
			)
		)
		(property "Author" "Antmicro"
			(at 368.3 104.14 0)
			(effects
				(font
					(size 1.27 1.27)
					(thickness 0.15)
				)
				(justify left bottom)
				(hide yes)
			)
		)
		(property "Val" "10n"
			(at 343.535 123.825 90)
			(effects
				(font
					(size 1.27 1.27)
					(thickness 0.15)
				)
				(justify right)
			)
		)
		(property "Voltage" "50V"
			(at 370.84 104.14 0)
			(effects
				(font
					(size 1.27 1.27)
				)
				(justify left bottom)
				(hide yes)
			)
		)
		(property "Dielectric" "X7R"
			(at 373.38 104.14 0)
			(effects
				(font
					(size 1.27 1.27)
				)
				(justify left bottom)
				(hide yes)
			)
		)
		(pin "1"
		)
		(pin "2"
		)
		(instances
			(project "gmsl-deserializer"
				(path ""
					(reference "C51")
					(unit 1)
				)
			)
		)
	)
	(symbol
		(lib_id "antmicroResistors0402:R_49R9_0402")
		(at 74.93 114.3 0)
		(mirror y)
		(unit 1)
		(exclude_from_sim no)
		(in_bom yes)
		(on_board yes)
		(dnp no)
		(property "Reference" "R45"
			(at 69.215 116.205 0)
			(effects
				(font
					(size 1.27 1.27)
					(thickness 0.15)
				)
			)
		)
		(property "Value" "R_49R9_0402"
			(at 54.61 127 0)
			(effects
				(font
					(size 1.27 1.27)
					(thickness 0.15)
				)
				(justify left bottom)
				(hide yes)
			)
		)
		(property "Footprint" "antmicro-footprints:R_0402_1005Metric"
			(at 54.61 129.54 0)
			(effects
				(font
					(size 1.27 1.27)
					(thickness 0.15)
				)
				(justify left bottom)
				(hide yes)
			)
		)
		(property "Datasheet" "https://www.bourns.com/docs/product-datasheets/cr.pdf"
			(at 54.61 132.08 0)
			(effects
				(font
					(size 1.27 1.27)
					(thickness 0.15)
				)
				(justify left bottom)
				(hide yes)
			)
		)
		(property "Description" "SMD Chip Resistor, 49.9 ohm, ± 1%, 62.5 mW, 0402 [1005 Metric], Thick Film, General Purpose"
			(at 74.93 114.3 0)
			(effects
				(font
					(size 1.27 1.27)
				)
				(hide yes)
			)
		)
		(property "MPN" "CR0402-FX-49R9GLF"
			(at 54.61 134.62 0)
			(effects
				(font
					(size 1.27 1.27)
					(thickness 0.15)
				)
				(justify left bottom)
				(hide yes)
			)
		)
		(property "Manufacturer" "Bourns"
			(at 54.61 137.16 0)
			(effects
				(font
					(size 1.27 1.27)
					(thickness 0.15)
				)
				(justify left bottom)
				(hide yes)
			)
		)
		(property "License" "Apache-2.0"
			(at 54.61 139.7 0)
			(effects
				(font
					(size 1.27 1.27)
					(thickness 0.15)
				)
				(justify left bottom)
				(hide yes)
			)
		)
		(property "Author" "Antmicro"
			(at 54.61 142.24 0)
			(effects
				(font
					(size 1.27 1.27)
					(thickness 0.15)
				)
				(justify left bottom)
				(hide yes)
			)
		)
		(property "Val" "49R9"
			(at 74.295 116.205 0)
			(effects
				(font
					(size 1.27 1.27)
					(thickness 0.15)
				)
			)
		)
		(property "Tolerance" "1%"
			(at 54.61 124.46 0)
			(effects
				(font
					(size 1.27 1.27)
				)
				(justify left bottom)
				(hide yes)
			)
		)
		(pin "1"
		)
		(pin "2"
		)
		(instances
			(project "gmsl-deserializer"
				(path ""
					(reference "R45")
					(unit 1)
				)
			)
		)
	)
	(symbol
		(lib_id "antmicroCapacitors0402:C_10n_0402")
		(at 341.63 102.87 90)
		(unit 1)
		(exclude_from_sim no)
		(in_bom yes)
		(on_board yes)
		(dnp no)
		(property "Reference" "C50"
			(at 342.265 98.425 90)
			(effects
				(font
					(size 1.27 1.27)
					(thickness 0.15)
				)
				(justify right)
			)
		)
		(property "Value" "C_10n_0402"
			(at 351.79 82.55 0)
			(effects
				(font
					(size 1.27 1.27)
					(thickness 0.15)
				)
				(justify left bottom)
				(hide yes)
			)
		)
		(property "Footprint" "antmicro-footprints:C_0402_1005Metric"
			(at 354.33 82.55 0)
			(effects
				(font
					(size 1.27 1.27)
					(thickness 0.15)
				)
				(justify left bottom)
				(hide yes)
			)
		)
		(property "Datasheet" "https://www.murata.com/products/productdetail?partno=GRM155R71H103KA88%23"
			(at 356.87 82.55 0)
			(effects
				(font
					(size 1.27 1.27)
					(thickness 0.15)
				)
				(justify left bottom)
				(hide yes)
			)
		)
		(property "Description" "SMD Multilayer Ceramic Capacitor, 10000 pF, 50 V, 0402 [1005 Metric], ± 10%, X7R, GRM Series"
			(at 341.63 102.87 0)
			(effects
				(font
					(size 1.27 1.27)
				)
				(hide yes)
			)
		)
		(property "MPN" "GRM155R71H103KA88D"
			(at 359.41 82.55 0)
			(effects
				(font
					(size 1.27 1.27)
					(thickness 0.15)
				)
				(justify left bottom)
				(hide yes)
			)
		)
		(property "Manufacturer" "Murata"
			(at 361.95 82.55 0)
			(effects
				(font
					(size 1.27 1.27)
					(thickness 0.15)
				)
				(justify left bottom)
				(hide yes)
			)
		)
		(property "License" "Apache-2.0"
			(at 364.49 82.55 0)
			(effects
				(font
					(size 1.27 1.27)
					(thickness 0.15)
				)
				(justify left bottom)
				(hide yes)
			)
		)
		(property "Author" "Antmicro"
			(at 367.03 82.55 0)
			(effects
				(font
					(size 1.27 1.27)
					(thickness 0.15)
				)
				(justify left bottom)
				(hide yes)
			)
		)
		(property "Val" "10n"
			(at 342.265 102.235 90)
			(effects
				(font
					(size 1.27 1.27)
					(thickness 0.15)
				)
				(justify right)
			)
		)
		(property "Voltage" "50V"
			(at 369.57 82.55 0)
			(effects
				(font
					(size 1.27 1.27)
				)
				(justify left bottom)
				(hide yes)
			)
		)
		(property "Dielectric" "X7R"
			(at 372.11 82.55 0)
			(effects
				(font
					(size 1.27 1.27)
				)
				(justify left bottom)
				(hide yes)
			)
		)
		(pin "1"
		)
		(pin "2"
		)
		(instances
			(project "gmsl-deserializer"
				(path ""
					(reference "C50")
					(unit 1)
				)
			)
		)
	)
)
